G04 ================== begin FILE IDENTIFICATION RECORD ==================*
G04 Layout Name:  D:/<user>/Wistron_project/16318-2/gbr/16318-2.brd*
G04 Film Name:    TSMD*
G04 File Format:  Gerber RS274X*
G04 File Origin:  Cadence Allegro 16.5-S056*
G04 Origin Date:  Mon Aug 07 11:09:28 2017*
G04 *
G04 Layer:  VIA CLASS/PASTEMASK_TOP*
G04 Layer:  PIN/PASTEMASK_TOP*
G04 Layer:  PACKAGE GEOMETRY/PASTEMASK_TOP*
G04 Layer:  DRAWING FORMAT/LAYER_PCB_STORY*
G04 Layer:  DRAWING FORMAT/LAYER_PAST_T*
G04 Layer:  BOARD GEOMETRY/PANEL_OUTLINE*
G04 *
G04 Offset:    (0.00 0.00)*
G04 Mirror:    No*
G04 Mode:      Positive*
G04 Rotation:  0*
G04 FullContactRelief:  No*
G04 UndefLineWidth:     6.00*
G04 ================== end FILE IDENTIFICATION RECORD ====================*
%FSLAX35Y35*MOIN*%
%IR0*IPPOS*OFA0.00000B0.00000*MIA0B0*SFA1.00000B1.00000*%
%AMMACRO49*
4,1,40,.013,.017,
-.013,.017,
-.013695,.016939,
-.014368,.016759,
-.015,.016464,
-.015571,.016064,
-.016064,.015571,
-.016464,.015,
-.016759,.014368,
-.016939,.013695,
-.017,.013,
-.017,-.013,
-.016939,-.013695,
-.016759,-.014368,
-.016464,-.015,
-.016064,-.015571,
-.015571,-.016064,
-.015,-.016464,
-.014368,-.016759,
-.013695,-.016939,
-.013,-.017,
.013,-.017,
.013695,-.016939,
.014368,-.016759,
.015,-.016464,
.015571,-.016064,
.016064,-.015571,
.016464,-.015,
.016759,-.014368,
.016939,-.013695,
.017,-.013,
.017,.013,
.016939,.013695,
.016759,.014368,
.016464,.015,
.016064,.015571,
.015571,.016064,
.015,.016464,
.014368,.016759,
.013695,.016939,
.013,.017,
0.0*
%
%ADD49MACRO49*%
%AMMACRO15*
4,1,40,.017,-.013,
.017,.013,
.016939,.013695,
.016759,.014368,
.016464,.015,
.016064,.015571,
.015571,.016064,
.015,.016464,
.014368,.016759,
.013695,.016939,
.013,.017,
-.013,.017,
-.013695,.016939,
-.014368,.016759,
-.015,.016464,
-.015571,.016064,
-.016064,.015571,
-.016464,.015,
-.016759,.014368,
-.016939,.013695,
-.017,.013,
-.017,-.013,
-.016939,-.013695,
-.016759,-.014368,
-.016464,-.015,
-.016064,-.015571,
-.015571,-.016064,
-.015,-.016464,
-.014368,-.016759,
-.013695,-.016939,
-.013,-.017,
.013,-.017,
.013695,-.016939,
.014368,-.016759,
.015,-.016464,
.015571,-.016064,
.016064,-.015571,
.016464,-.015,
.016759,-.014368,
.016939,-.013695,
.017,-.013,
0.0*
%
%ADD15MACRO15*%
%AMMACRO72*
4,1,40,.008,.009,
.008695,.008939,
.009368,.008759,
.01,.008464,
.010571,.008064,
.011064,.007571,
.011464,.007,
.011759,.006368,
.011939,.005695,
.012,.005,
.012,-.005,
.011939,-.005695,
.011759,-.006368,
.011464,-.007,
.011064,-.007571,
.010571,-.008064,
.01,-.008464,
.009368,-.008759,
.008695,-.008939,
.008,-.009,
-.008,-.009,
-.008695,-.008939,
-.009368,-.008759,
-.01,-.008464,
-.010571,-.008064,
-.011064,-.007571,
-.011464,-.007,
-.011759,-.006368,
-.011939,-.005695,
-.012,-.005,
-.012,.005,
-.011939,.005695,
-.011759,.006368,
-.011464,.007,
-.011064,.007571,
-.010571,.008064,
-.01,.008464,
-.009368,.008759,
-.008695,.008939,
-.008,.009,
.008,.009,
0.0*
%
%ADD72MACRO72*%
%AMMACRO103*
4,1,3,-.0125,.025,
.0125,0.0,
-.0125,-.025,
-.0125,.025,
0.0*
%
%ADD103MACRO103*%
%AMMACRO58*
4,1,15,-.0275,-.115,
-.0275,.02323,
-.02431,.026923,
-.021809,.031114,
-.020074,.035675,
-.019157,.040469,
-.019087,.045348,
-.019865,.050166,
-.021468,.054776,
-.023847,.059037,
-.02693,.06282,
-.0275,.06339,
-.0275,.115,
.0275,.115,
.0275,-.115,
-.0275,-.115,
0.0*
%
%ADD58MACRO58*%
%AMMACRO41*
4,1,3,.025,.0125,
0.0,-.0125,
-.025,.0125,
.025,.0125,
0.0*
%
%ADD41MACRO41*%
%ADD116R,.143X.011*%
%ADD39C,.04*%
%AMMACRO120*
4,1,40,-.007,.004,
-.007,-.004,
-.00697,-.004347,
-.006879,-.004684,
-.006732,-.005,
-.006532,-.005286,
-.006286,-.005532,
-.006,-.005732,
-.005684,-.005879,
-.005347,-.00597,
-.005,-.006,
.005,-.006,
.005347,-.00597,
.005684,-.005879,
.006,-.005732,
.006286,-.005532,
.006532,-.005286,
.006732,-.005,
.006879,-.004684,
.00697,-.004347,
.007,-.004,
.007,.004,
.00697,.004347,
.006879,.004684,
.006732,.005,
.006532,.005286,
.006286,.005532,
.006,.005732,
.005684,.005879,
.005347,.00597,
.005,.006,
-.005,.006,
-.005347,.00597,
-.005684,.005879,
-.006,.005732,
-.006286,.005532,
-.006532,.005286,
-.006732,.005,
-.006879,.004684,
-.00697,.004347,
-.007,.004,
0.0*
%
%ADD120MACRO120*%
%ADD22C,.014*%
%ADD44C,.016*%
%ADD23C,.026*%
%ADD38C,.028*%
%ADD114R,.128X.098*%
%ADD104R,.062X.062*%
%AMMACRO56*
4,1,40,.0225,-.007,
.022378,-.008389,
.022018,-.009736,
.021428,-.011,
.020628,-.012142,
.019642,-.013128,
.0185,-.013928,
.017236,-.014518,
.015889,-.014878,
.0145,-.015,
-.0145,-.015,
-.015889,-.014878,
-.017236,-.014518,
-.0185,-.013928,
-.019642,-.013128,
-.020628,-.012142,
-.021428,-.011,
-.022018,-.009736,
-.022378,-.008389,
-.0225,-.007,
-.0225,.007,
-.022378,.008389,
-.022018,.009736,
-.021428,.011,
-.020628,.012142,
-.019642,.013128,
-.0185,.013928,
-.017236,.014518,
-.015889,.014878,
-.0145,.015,
.0145,.015,
.015889,.014878,
.017236,.014518,
.0185,.013928,
.019642,.013128,
.020628,.012142,
.021428,.011,
.022018,.009736,
.022378,.008389,
.0225,.007,
.0225,-.007,
0.0*
%
%ADD56MACRO56*%
%AMMACRO66*
4,1,40,-.007,-.0225,
-.008389,-.022378,
-.009736,-.022018,
-.011,-.021428,
-.012142,-.020628,
-.013128,-.019642,
-.013928,-.0185,
-.014518,-.017236,
-.014878,-.015889,
-.015,-.0145,
-.015,.0145,
-.014878,.015889,
-.014518,.017236,
-.013928,.0185,
-.013128,.019642,
-.012142,.020628,
-.011,.021428,
-.009736,.022018,
-.008389,.022378,
-.007,.0225,
.007,.0225,
.008389,.022378,
.009736,.022018,
.011,.021428,
.012142,.020628,
.013128,.019642,
.013928,.0185,
.014518,.017236,
.014878,.015889,
.015,.0145,
.015,-.0145,
.014878,-.015889,
.014518,-.017236,
.013928,-.0185,
.013128,-.019642,
.012142,-.020628,
.011,-.021428,
.009736,-.022018,
.008389,-.022378,
.007,-.0225,
-.007,-.0225,
0.0*
%
%ADD66MACRO66*%
%AMMACRO20*
4,1,40,.007,.011,
-.007,.011,
-.007695,.010939,
-.008368,.010759,
-.009,.010464,
-.009571,.010064,
-.010064,.009571,
-.010464,.009,
-.010759,.008368,
-.010939,.007695,
-.011,.007,
-.011,-.007,
-.010939,-.007695,
-.010759,-.008368,
-.010464,-.009,
-.010064,-.009571,
-.009571,-.010064,
-.009,-.010464,
-.008368,-.010759,
-.007695,-.010939,
-.007,-.011,
.007,-.011,
.007695,-.010939,
.008368,-.010759,
.009,-.010464,
.009571,-.010064,
.010064,-.009571,
.010464,-.009,
.010759,-.008368,
.010939,-.007695,
.011,-.007,
.011,.007,
.010939,.007695,
.010759,.008368,
.010464,.009,
.010064,.009571,
.009571,.010064,
.009,.010464,
.008368,.010759,
.007695,.010939,
.007,.011,
0.0*
%
%ADD20MACRO20*%
%AMMACRO12*
4,1,40,.011,-.007,
.011,.007,
.010939,.007695,
.010759,.008368,
.010464,.009,
.010064,.009571,
.009571,.010064,
.009,.010464,
.008368,.010759,
.007695,.010939,
.007,.011,
-.007,.011,
-.007695,.010939,
-.008368,.010759,
-.009,.010464,
-.009571,.010064,
-.010064,.009571,
-.010464,.009,
-.010759,.008368,
-.010939,.007695,
-.011,.007,
-.011,-.007,
-.010939,-.007695,
-.010759,-.008368,
-.010464,-.009,
-.010064,-.009571,
-.009571,-.010064,
-.009,-.010464,
-.008368,-.010759,
-.007695,-.010939,
-.007,-.011,
.007,-.011,
.007695,-.010939,
.008368,-.010759,
.009,-.010464,
.009571,-.010064,
.010064,-.009571,
.010464,-.009,
.010759,-.008368,
.010939,-.007695,
.011,-.007,
0.0*
%
%ADD12MACRO12*%
%AMMACRO29*
4,1,40,-.012,.008,
-.012,-.008,
-.011939,-.008695,
-.011759,-.009368,
-.011464,-.01,
-.011064,-.010571,
-.010571,-.011064,
-.01,-.011464,
-.009368,-.011759,
-.008695,-.011939,
-.008,-.012,
.008,-.012,
.008695,-.011939,
.009368,-.011759,
.01,-.011464,
.010571,-.011064,
.011064,-.010571,
.011464,-.01,
.011759,-.009368,
.011939,-.008695,
.012,-.008,
.012,.008,
.011939,.008695,
.011759,.009368,
.011464,.01,
.011064,.010571,
.010571,.011064,
.01,.011464,
.009368,.011759,
.008695,.011939,
.008,.012,
-.008,.012,
-.008695,.011939,
-.009368,.011759,
-.01,.011464,
-.010571,.011064,
-.011064,.010571,
-.011464,.01,
-.011759,.009368,
-.011939,.008695,
-.012,.008,
0.0*
%
%ADD29MACRO29*%
%AMMACRO31*
4,1,40,.008,.012,
-.008,.012,
-.008695,.011939,
-.009368,.011759,
-.01,.011464,
-.010571,.011064,
-.011064,.010571,
-.011464,.01,
-.011759,.009368,
-.011939,.008695,
-.012,.008,
-.012,-.008,
-.011939,-.008695,
-.011759,-.009368,
-.011464,-.01,
-.011064,-.010571,
-.010571,-.011064,
-.01,-.011464,
-.009368,-.011759,
-.008695,-.011939,
-.008,-.012,
.008,-.012,
.008695,-.011939,
.009368,-.011759,
.01,-.011464,
.010571,-.011064,
.011064,-.010571,
.011464,-.01,
.011759,-.009368,
.011939,-.008695,
.012,-.008,
.012,.008,
.011939,.008695,
.011759,.009368,
.011464,.01,
.011064,.010571,
.010571,.011064,
.01,.011464,
.009368,.011759,
.008695,.011939,
.008,.012,
0.0*
%
%ADD31MACRO31*%
%AMMACRO74*
4,1,40,-.013,-.017,
.013,-.017,
.013695,-.016939,
.014368,-.016759,
.015,-.016464,
.015571,-.016064,
.016064,-.015571,
.016464,-.015,
.016759,-.014368,
.016939,-.013695,
.017,-.013,
.017,.013,
.016939,.013695,
.016759,.014368,
.016464,.015,
.016064,.015571,
.015571,.016064,
.015,.016464,
.014368,.016759,
.013695,.016939,
.013,.017,
-.013,.017,
-.013695,.016939,
-.014368,.016759,
-.015,.016464,
-.015571,.016064,
-.016064,.015571,
-.016464,.015,
-.016759,.014368,
-.016939,.013695,
-.017,.013,
-.017,-.013,
-.016939,-.013695,
-.016759,-.014368,
-.016464,-.015,
-.016064,-.015571,
-.015571,-.016064,
-.015,-.016464,
-.014368,-.016759,
-.013695,-.016939,
-.013,-.017,
0.0*
%
%ADD74MACRO74*%
%AMMACRO80*
4,1,40,-.017,.013,
-.017,-.013,
-.016939,-.013695,
-.016759,-.014368,
-.016464,-.015,
-.016064,-.015571,
-.015571,-.016064,
-.015,-.016464,
-.014368,-.016759,
-.013695,-.016939,
-.013,-.017,
.013,-.017,
.013695,-.016939,
.014368,-.016759,
.015,-.016464,
.015571,-.016064,
.016064,-.015571,
.016464,-.015,
.016759,-.014368,
.016939,-.013695,
.017,-.013,
.017,.013,
.016939,.013695,
.016759,.014368,
.016464,.015,
.016064,.015571,
.015571,.016064,
.015,.016464,
.014368,.016759,
.013695,.016939,
.013,.017,
-.013,.017,
-.013695,.016939,
-.014368,.016759,
-.015,.016464,
-.015571,.016064,
-.016064,.015571,
-.016464,.015,
-.016759,.014368,
-.016939,.013695,
-.017,.013,
0.0*
%
%ADD80MACRO80*%
%AMMACRO70*
4,1,40,-.009,.008,
-.008939,.008695,
-.008759,.009368,
-.008464,.01,
-.008064,.010571,
-.007571,.011064,
-.007,.011464,
-.006368,.011759,
-.005695,.011939,
-.005,.012,
.005,.012,
.005695,.011939,
.006368,.011759,
.007,.011464,
.007571,.011064,
.008064,.010571,
.008464,.01,
.008759,.009368,
.008939,.008695,
.009,.008,
.009,-.008,
.008939,-.008695,
.008759,-.009368,
.008464,-.01,
.008064,-.010571,
.007571,-.011064,
.007,-.011464,
.006368,-.011759,
.005695,-.011939,
.005,-.012,
-.005,-.012,
-.005695,-.011939,
-.006368,-.011759,
-.007,-.011464,
-.007571,-.011064,
-.008064,-.010571,
-.008464,-.01,
-.008759,-.009368,
-.008939,-.008695,
-.009,-.008,
-.009,.008,
0.0*
%
%ADD70MACRO70*%
%AMMACRO71*
4,1,40,.008,.009,
.008695,.008939,
.009368,.008759,
.01,.008464,
.010571,.008064,
.011064,.007571,
.011464,.007,
.011759,.006368,
.011939,.005695,
.012,.005,
.012,-.005,
.011939,-.005695,
.011759,-.006368,
.011464,-.007,
.011064,-.007571,
.010571,-.008064,
.01,-.008464,
.009368,-.008759,
.008695,-.008939,
.008,-.009,
-.008,-.009,
-.008695,-.008939,
-.009368,-.008759,
-.01,-.008464,
-.010571,-.008064,
-.011064,-.007571,
-.011464,-.007,
-.011759,-.006368,
-.011939,-.005695,
-.012,-.005,
-.012,.005,
-.011939,.005695,
-.011759,.006368,
-.011464,.007,
-.011064,.007571,
-.010571,.008064,
-.01,.008464,
-.009368,.008759,
-.008695,.008939,
-.008,.009,
.008,.009,
0.0*
%
%ADD71MACRO71*%
%AMMACRO21*
4,1,40,.007,.011,
-.007,.011,
-.007695,.010939,
-.008368,.010759,
-.009,.010464,
-.009571,.010064,
-.010064,.009571,
-.010464,.009,
-.010759,.008368,
-.010939,.007695,
-.011,.007,
-.011,-.007,
-.010939,-.007695,
-.010759,-.008368,
-.010464,-.009,
-.010064,-.009571,
-.009571,-.010064,
-.009,-.010464,
-.008368,-.010759,
-.007695,-.010939,
-.007,-.011,
.007,-.011,
.007695,-.010939,
.008368,-.010759,
.009,-.010464,
.009571,-.010064,
.010064,-.009571,
.010464,-.009,
.010759,-.008368,
.010939,-.007695,
.011,-.007,
.011,.007,
.010939,.007695,
.010759,.008368,
.010464,.009,
.010064,.009571,
.009571,.010064,
.009,.010464,
.008368,.010759,
.007695,.010939,
.007,.011,
0.0*
%
%ADD21MACRO21*%
%AMMACRO13*
4,1,40,.011,-.007,
.011,.007,
.010939,.007695,
.010759,.008368,
.010464,.009,
.010064,.009571,
.009571,.010064,
.009,.010464,
.008368,.010759,
.007695,.010939,
.007,.011,
-.007,.011,
-.007695,.010939,
-.008368,.010759,
-.009,.010464,
-.009571,.010064,
-.010064,.009571,
-.010464,.009,
-.010759,.008368,
-.010939,.007695,
-.011,.007,
-.011,-.007,
-.010939,-.007695,
-.010759,-.008368,
-.010464,-.009,
-.010064,-.009571,
-.009571,-.010064,
-.009,-.010464,
-.008368,-.010759,
-.007695,-.010939,
-.007,-.011,
.007,-.011,
.007695,-.010939,
.008368,-.010759,
.009,-.010464,
.009571,-.010064,
.010064,-.009571,
.010464,-.009,
.010759,-.008368,
.010939,-.007695,
.011,-.007,
0.0*
%
%ADD13MACRO13*%
%AMMACRO111*
4,1,20,-.1075,-.0635,
-.1075,-.049,
-.118,-.049,
-.118,-.0395,
-.1075,-.0395,
-.1075,.0395,
-.118,.0395,
-.118,.049,
-.1075,.049,
-.1075,.0635,
.1075,.0635,
.1075,.049,
.118,.049,
.118,.0395,
.1075,.0395,
.1075,-.0395,
.118,-.0395,
.118,-.049,
.1075,-.049,
.1075,-.0635,
-.1075,-.0635,
0.0*
%
%ADD111MACRO111*%
%AMMACRO28*
4,1,40,-.012,.008,
-.012,-.008,
-.011939,-.008695,
-.011759,-.009368,
-.011464,-.01,
-.011064,-.010571,
-.010571,-.011064,
-.01,-.011464,
-.009368,-.011759,
-.008695,-.011939,
-.008,-.012,
.008,-.012,
.008695,-.011939,
.009368,-.011759,
.01,-.011464,
.010571,-.011064,
.011064,-.010571,
.011464,-.01,
.011759,-.009368,
.011939,-.008695,
.012,-.008,
.012,.008,
.011939,.008695,
.011759,.009368,
.011464,.01,
.011064,.010571,
.010571,.011064,
.01,.011464,
.009368,.011759,
.008695,.011939,
.008,.012,
-.008,.012,
-.008695,.011939,
-.009368,.011759,
-.01,.011464,
-.010571,.011064,
-.011064,.010571,
-.011464,.01,
-.011759,.009368,
-.011939,.008695,
-.012,.008,
0.0*
%
%ADD28MACRO28*%
%AMMACRO30*
4,1,40,.008,.012,
-.008,.012,
-.008695,.011939,
-.009368,.011759,
-.01,.011464,
-.010571,.011064,
-.011064,.010571,
-.011464,.01,
-.011759,.009368,
-.011939,.008695,
-.012,.008,
-.012,-.008,
-.011939,-.008695,
-.011759,-.009368,
-.011464,-.01,
-.011064,-.010571,
-.010571,-.011064,
-.01,-.011464,
-.009368,-.011759,
-.008695,-.011939,
-.008,-.012,
.008,-.012,
.008695,-.011939,
.009368,-.011759,
.01,-.011464,
.010571,-.011064,
.011064,-.010571,
.011464,-.01,
.011759,-.009368,
.011939,-.008695,
.012,-.008,
.012,.008,
.011939,.008695,
.011759,.009368,
.011464,.01,
.011064,.010571,
.010571,.011064,
.01,.011464,
.009368,.011759,
.008695,.011939,
.008,.012,
0.0*
%
%ADD30MACRO30*%
%AMMACRO75*
4,1,40,-.013,-.017,
.013,-.017,
.013695,-.016939,
.014368,-.016759,
.015,-.016464,
.015571,-.016064,
.016064,-.015571,
.016464,-.015,
.016759,-.014368,
.016939,-.013695,
.017,-.013,
.017,.013,
.016939,.013695,
.016759,.014368,
.016464,.015,
.016064,.015571,
.015571,.016064,
.015,.016464,
.014368,.016759,
.013695,.016939,
.013,.017,
-.013,.017,
-.013695,.016939,
-.014368,.016759,
-.015,.016464,
-.015571,.016064,
-.016064,.015571,
-.016464,.015,
-.016759,.014368,
-.016939,.013695,
-.017,.013,
-.017,-.013,
-.016939,-.013695,
-.016759,-.014368,
-.016464,-.015,
-.016064,-.015571,
-.015571,-.016064,
-.015,-.016464,
-.014368,-.016759,
-.013695,-.016939,
-.013,-.017,
0.0*
%
%ADD75MACRO75*%
%AMMACRO81*
4,1,40,-.017,.013,
-.017,-.013,
-.016939,-.013695,
-.016759,-.014368,
-.016464,-.015,
-.016064,-.015571,
-.015571,-.016064,
-.015,-.016464,
-.014368,-.016759,
-.013695,-.016939,
-.013,-.017,
.013,-.017,
.013695,-.016939,
.014368,-.016759,
.015,-.016464,
.015571,-.016064,
.016064,-.015571,
.016464,-.015,
.016759,-.014368,
.016939,-.013695,
.017,-.013,
.017,.013,
.016939,.013695,
.016759,.014368,
.016464,.015,
.016064,.015571,
.015571,.016064,
.015,.016464,
.014368,.016759,
.013695,.016939,
.013,.017,
-.013,.017,
-.013695,.016939,
-.014368,.016759,
-.015,.016464,
-.015571,.016064,
-.016064,.015571,
-.016464,.015,
-.016759,.014368,
-.016939,.013695,
-.017,.013,
0.0*
%
%ADD81MACRO81*%
%AMMACRO69*
4,1,40,.009,-.008,
.008939,-.008695,
.008759,-.009368,
.008464,-.01,
.008064,-.010571,
.007571,-.011064,
.007,-.011464,
.006368,-.011759,
.005695,-.011939,
.005,-.012,
-.005,-.012,
-.005695,-.011939,
-.006368,-.011759,
-.007,-.011464,
-.007571,-.011064,
-.008064,-.010571,
-.008464,-.01,
-.008759,-.009368,
-.008939,-.008695,
-.009,-.008,
-.009,.008,
-.008939,.008695,
-.008759,.009368,
-.008464,.01,
-.008064,.010571,
-.007571,.011064,
-.007,.011464,
-.006368,.011759,
-.005695,.011939,
-.005,.012,
.005,.012,
.005695,.011939,
.006368,.011759,
.007,.011464,
.007571,.011064,
.008064,.010571,
.008464,.01,
.008759,.009368,
.008939,.008695,
.009,.008,
.009,-.008,
0.0*
%
%ADD69MACRO69*%
%ADD118R,.011X.03*%
%ADD117R,.03X.011*%
%AMMACRO77*
4,1,40,-.008,-.009,
-.008695,-.008939,
-.009368,-.008759,
-.01,-.008464,
-.010571,-.008064,
-.011064,-.007571,
-.011464,-.007,
-.011759,-.006368,
-.011939,-.005695,
-.012,-.005,
-.012,.005,
-.011939,.005695,
-.011759,.006368,
-.011464,.007,
-.011064,.007571,
-.010571,.008064,
-.01,.008464,
-.009368,.008759,
-.008695,.008939,
-.008,.009,
.008,.009,
.008695,.008939,
.009368,.008759,
.01,.008464,
.010571,.008064,
.011064,.007571,
.011464,.007,
.011759,.006368,
.011939,.005695,
.012,.005,
.012,-.005,
.011939,-.005695,
.011759,-.006368,
.011464,-.007,
.011064,-.007571,
.010571,-.008064,
.01,-.008464,
.009368,-.008759,
.008695,-.008939,
.008,-.009,
-.008,-.009,
0.0*
%
%ADD77MACRO77*%
%ADD86R,.05X.012*%
%ADD85R,.012X.05*%
%ADD76R,.06X.02*%
%ADD61R,.04X.022*%
%AMMACRO102*
4,1,3,-.0125,0.0,
.0125,.025,
.0125,-.025,
-.0125,0.0,
0.0*
%
%ADD102MACRO102*%
%ADD91R,.042X.012*%
%ADD89R,.012X.042*%
%ADD65R,.06X.012*%
%AMMACRO40*
4,1,3,0.0,.0125,
.025,-.0125,
-.025,-.0125,
0.0,.0125,
0.0*
%
%ADD40MACRO40*%
%ADD16R,.022X.04*%
%ADD100R,.012X.06*%
%ADD84R,.043X.012*%
%ADD83R,.012X.043*%
%ADD63R,.06X.014*%
%ADD62R,.081X.02*%
%ADD54R,.04X.016*%
%ADD43R,.044X.012*%
%ADD33R,.042X.014*%
%ADD27R,.014X.042*%
%ADD119R,.032X.016*%
%ADD112R,.012X.044*%
%ADD99R,.014X.06*%
%ADD90R,.036X.012*%
%ADD88R,.012X.036*%
%ADD53R,.105X.128*%
%ADD107R,.012X.036*%
%ADD105R,.036X.012*%
%ADD97R,.016X.032*%
%ADD94R,.064X.03*%
%ADD93R,.03X.045*%
%ADD115R,.093X.011*%
%ADD113R,.128X.133*%
%ADD108R,.012X.037*%
%ADD106R,.037X.012*%
%ADD34R,.066X.02*%
%ADD60R,.05X.065*%
%ADD82R,.055X.042*%
%ADD68R,.026X.036*%
%ADD17R,.065X.05*%
%ADD121R,.029X.043*%
%ADD35R,.065X.025*%
%ADD96R,.09X.045*%
%ADD78R,.025X.065*%
%ADD64R,.048X.016*%
%ADD37R,.045X.055*%
%ADD92R,.13X.13*%
%ADD57R,.016X.048*%
%ADD36R,.055X.036*%
%ADD26R,.055X.045*%
%ADD122R,.06X.095*%
%ADD110R,.054X.074*%
%ADD109R,.09X.095*%
%ADD79R,.059X.045*%
%ADD51R,.024X.079*%
%AMMACRO98*
4,1,40,.007,.0225,
.008389,.022378,
.009736,.022018,
.011,.021428,
.012142,.020628,
.013128,.019642,
.013928,.0185,
.014518,.017236,
.014878,.015889,
.015,.0145,
.015,-.0145,
.014878,-.015889,
.014518,-.017236,
.013928,-.0185,
.013128,-.019642,
.012142,-.020628,
.011,-.021428,
.009736,-.022018,
.008389,-.022378,
.007,-.0225,
-.007,-.0225,
-.008389,-.022378,
-.009736,-.022018,
-.011,-.021428,
-.012142,-.020628,
-.013128,-.019642,
-.013928,-.0185,
-.014518,-.017236,
-.014878,-.015889,
-.015,-.0145,
-.015,.0145,
-.014878,.015889,
-.014518,.017236,
-.013928,.0185,
-.013128,.019642,
-.012142,.020628,
-.011,.021428,
-.009736,.022018,
-.008389,.022378,
-.007,.0225,
.007,.0225,
0.0*
%
%ADD98MACRO98*%
%ADD95R,.045X.059*%
%ADD87R,.152X.152*%
%AMMACRO67*
4,1,40,.014,.008,
.014,-.008,
.013939,-.008695,
.013759,-.009368,
.013464,-.01,
.013064,-.010571,
.012571,-.011064,
.012,-.011464,
.011368,-.011759,
.010695,-.011939,
.01,-.012,
-.01,-.012,
-.010695,-.011939,
-.011368,-.011759,
-.012,-.011464,
-.012571,-.011064,
-.013064,-.010571,
-.013464,-.01,
-.013759,-.009368,
-.013939,-.008695,
-.014,-.008,
-.014,.008,
-.013939,.008695,
-.013759,.009368,
-.013464,.01,
-.013064,.010571,
-.012571,.011064,
-.012,.011464,
-.011368,.011759,
-.010695,.011939,
-.01,.012,
.01,.012,
.010695,.011939,
.011368,.011759,
.012,.011464,
.012571,.011064,
.013064,.010571,
.013464,.01,
.013759,.009368,
.013939,.008695,
.014,.008,
0.0*
%
%ADD67MACRO67*%
%AMMACRO59*
4,1,40,-.008,.014,
.008,.014,
.008695,.013939,
.009368,.013759,
.01,.013464,
.010571,.013064,
.011064,.012571,
.011464,.012,
.011759,.011368,
.011939,.010695,
.012,.01,
.012,-.01,
.011939,-.010695,
.011759,-.011368,
.011464,-.012,
.011064,-.012571,
.010571,-.013064,
.01,-.013464,
.009368,-.013759,
.008695,-.013939,
.008,-.014,
-.008,-.014,
-.008695,-.013939,
-.009368,-.013759,
-.01,-.013464,
-.010571,-.013064,
-.011064,-.012571,
-.011464,-.012,
-.011759,-.011368,
-.011939,-.010695,
-.012,-.01,
-.012,.01,
-.011939,.010695,
-.011759,.011368,
-.011464,.012,
-.011064,.012571,
-.010571,.013064,
-.01,.013464,
-.009368,.013759,
-.008695,.013939,
-.008,.014,
0.0*
%
%ADD59MACRO59*%
%AMMACRO55*
4,1,40,-.0225,.007,
-.022378,.008389,
-.022018,.009736,
-.021428,.011,
-.020628,.012142,
-.019642,.013128,
-.0185,.013928,
-.017236,.014518,
-.015889,.014878,
-.0145,.015,
.0145,.015,
.015889,.014878,
.017236,.014518,
.0185,.013928,
.019642,.013128,
.020628,.012142,
.021428,.011,
.022018,.009736,
.022378,.008389,
.0225,.007,
.0225,-.007,
.022378,-.008389,
.022018,-.009736,
.021428,-.011,
.020628,-.012142,
.019642,-.013128,
.0185,-.013928,
.017236,-.014518,
.015889,-.014878,
.0145,-.015,
-.0145,-.015,
-.015889,-.014878,
-.017236,-.014518,
-.0185,-.013928,
-.019642,-.013128,
-.020628,-.012142,
-.021428,-.011,
-.022018,-.009736,
-.022378,-.008389,
-.0225,-.007,
-.0225,.007,
0.0*
%
%ADD55MACRO55*%
%ADD52R,.095X.09*%
%ADD101R,.069X.083*%
%ADD32R,.128X.128*%
%AMMACRO46*
4,1,40,-.008,-.012,
.008,-.012,
.008695,-.011939,
.009368,-.011759,
.01,-.011464,
.010571,-.011064,
.011064,-.010571,
.011464,-.01,
.011759,-.009368,
.011939,-.008695,
.012,-.008,
.012,.008,
.011939,.008695,
.011759,.009368,
.011464,.01,
.011064,.010571,
.010571,.011064,
.01,.011464,
.009368,.011759,
.008695,.011939,
.008,.012,
-.008,.012,
-.008695,.011939,
-.009368,.011759,
-.01,.011464,
-.010571,.011064,
-.011064,.010571,
-.011464,.01,
-.011759,.009368,
-.011939,.008695,
-.012,.008,
-.012,-.008,
-.011939,-.008695,
-.011759,-.009368,
-.011464,-.01,
-.011064,-.010571,
-.010571,-.011064,
-.01,-.011464,
-.009368,-.011759,
-.008695,-.011939,
-.008,-.012,
0.0*
%
%ADD46MACRO46*%
%AMMACRO25*
4,1,40,.012,-.008,
.012,.008,
.011939,.008695,
.011759,.009368,
.011464,.01,
.011064,.010571,
.010571,.011064,
.01,.011464,
.009368,.011759,
.008695,.011939,
.008,.012,
-.008,.012,
-.008695,.011939,
-.009368,.011759,
-.01,.011464,
-.010571,.011064,
-.011064,.010571,
-.011464,.01,
-.011759,.009368,
-.011939,.008695,
-.012,.008,
-.012,-.008,
-.011939,-.008695,
-.011759,-.009368,
-.011464,-.01,
-.011064,-.010571,
-.010571,-.011064,
-.01,-.011464,
-.009368,-.011759,
-.008695,-.011939,
-.008,-.012,
.008,-.012,
.008695,-.011939,
.009368,-.011759,
.01,-.011464,
.010571,-.011064,
.011064,-.010571,
.011464,-.01,
.011759,-.009368,
.011939,-.008695,
.012,-.008,
0.0*
%
%ADD25MACRO25*%
%AMMACRO18*
4,1,40,-.007,-.011,
.007,-.011,
.007695,-.010939,
.008368,-.010759,
.009,-.010464,
.009571,-.010064,
.010064,-.009571,
.010464,-.009,
.010759,-.008368,
.010939,-.007695,
.011,-.007,
.011,.007,
.010939,.007695,
.010759,.008368,
.010464,.009,
.010064,.009571,
.009571,.010064,
.009,.010464,
.008368,.010759,
.007695,.010939,
.007,.011,
-.007,.011,
-.007695,.010939,
-.008368,.010759,
-.009,.010464,
-.009571,.010064,
-.010064,.009571,
-.010464,.009,
-.010759,.008368,
-.010939,.007695,
-.011,.007,
-.011,-.007,
-.010939,-.007695,
-.010759,-.008368,
-.010464,-.009,
-.010064,-.009571,
-.009571,-.010064,
-.009,-.010464,
-.008368,-.010759,
-.007695,-.010939,
-.007,-.011,
0.0*
%
%ADD18MACRO18*%
%AMMACRO10*
4,1,40,-.011,.007,
-.011,-.007,
-.010939,-.007695,
-.010759,-.008368,
-.010464,-.009,
-.010064,-.009571,
-.009571,-.010064,
-.009,-.010464,
-.008368,-.010759,
-.007695,-.010939,
-.007,-.011,
.007,-.011,
.007695,-.010939,
.008368,-.010759,
.009,-.010464,
.009571,-.010064,
.010064,-.009571,
.010464,-.009,
.010759,-.008368,
.010939,-.007695,
.011,-.007,
.011,.007,
.010939,.007695,
.010759,.008368,
.010464,.009,
.010064,.009571,
.009571,.010064,
.009,.010464,
.008368,.010759,
.007695,.010939,
.007,.011,
-.007,.011,
-.007695,.010939,
-.008368,.010759,
-.009,.010464,
-.009571,.010064,
-.010064,.009571,
-.010464,.009,
-.010759,.008368,
-.010939,.007695,
-.011,.007,
0.0*
%
%ADD10MACRO10*%
%AMMACRO48*
4,1,40,.013,.017,
-.013,.017,
-.013695,.016939,
-.014368,.016759,
-.015,.016464,
-.015571,.016064,
-.016064,.015571,
-.016464,.015,
-.016759,.014368,
-.016939,.013695,
-.017,.013,
-.017,-.013,
-.016939,-.013695,
-.016759,-.014368,
-.016464,-.015,
-.016064,-.015571,
-.015571,-.016064,
-.015,-.016464,
-.014368,-.016759,
-.013695,-.016939,
-.013,-.017,
.013,-.017,
.013695,-.016939,
.014368,-.016759,
.015,-.016464,
.015571,-.016064,
.016064,-.015571,
.016464,-.015,
.016759,-.014368,
.016939,-.013695,
.017,-.013,
.017,.013,
.016939,.013695,
.016759,.014368,
.016464,.015,
.016064,.015571,
.015571,.016064,
.015,.016464,
.014368,.016759,
.013695,.016939,
.013,.017,
0.0*
%
%ADD48MACRO48*%
%AMMACRO14*
4,1,40,.017,-.013,
.017,.013,
.016939,.013695,
.016759,.014368,
.016464,.015,
.016064,.015571,
.015571,.016064,
.015,.016464,
.014368,.016759,
.013695,.016939,
.013,.017,
-.013,.017,
-.013695,.016939,
-.014368,.016759,
-.015,.016464,
-.015571,.016064,
-.016064,.015571,
-.016464,.015,
-.016759,.014368,
-.016939,.013695,
-.017,.013,
-.017,-.013,
-.016939,-.013695,
-.016759,-.014368,
-.016464,-.015,
-.016064,-.015571,
-.015571,-.016064,
-.015,-.016464,
-.014368,-.016759,
-.013695,-.016939,
-.013,-.017,
.013,-.017,
.013695,-.016939,
.014368,-.016759,
.015,-.016464,
.015571,-.016064,
.016064,-.015571,
.016464,-.015,
.016759,-.014368,
.016939,-.013695,
.017,-.013,
0.0*
%
%ADD14MACRO14*%
%AMMACRO73*
4,1,40,-.008,-.009,
-.008695,-.008939,
-.009368,-.008759,
-.01,-.008464,
-.010571,-.008064,
-.011064,-.007571,
-.011464,-.007,
-.011759,-.006368,
-.011939,-.005695,
-.012,-.005,
-.012,.005,
-.011939,.005695,
-.011759,.006368,
-.011464,.007,
-.011064,.007571,
-.010571,.008064,
-.01,.008464,
-.009368,.008759,
-.008695,.008939,
-.008,.009,
.008,.009,
.008695,.008939,
.009368,.008759,
.01,.008464,
.010571,.008064,
.011064,.007571,
.011464,.007,
.011759,.006368,
.011939,.005695,
.012,.005,
.012,-.005,
.011939,-.005695,
.011759,-.006368,
.011464,-.007,
.011064,-.007571,
.010571,-.008064,
.01,-.008464,
.009368,-.008759,
.008695,-.008939,
.008,-.009,
-.008,-.009,
0.0*
%
%ADD73MACRO73*%
%AMMACRO42*
4,1,20,-.0635,.1075,
-.049,.1075,
-.049,.118,
-.0395,.118,
-.0395,.1075,
.0395,.1075,
.0395,.118,
.049,.118,
.049,.1075,
.0635,.1075,
.0635,-.1075,
.049,-.1075,
.049,-.118,
.0395,-.118,
.0395,-.1075,
-.0395,-.1075,
-.0395,-.118,
-.049,-.118,
-.049,-.1075,
-.0635,-.1075,
-.0635,.1075,
0.0*
%
%ADD42MACRO42*%
%AMMACRO50*
4,1,15,-.0275,-.115,
-.0275,.115,
.0275,.115,
.0275,.06339,
.02431,.059697,
.021809,.055506,
.020074,.050945,
.019157,.046151,
.019087,.041272,
.019865,.036454,
.021468,.031844,
.023847,.027583,
.02693,.0238,
.0275,.02323,
.0275,-.115,
-.0275,-.115,
0.0*
%
%ADD50MACRO50*%
%AMMACRO45*
4,1,40,-.008,-.012,
.008,-.012,
.008695,-.011939,
.009368,-.011759,
.01,-.011464,
.010571,-.011064,
.011064,-.010571,
.011464,-.01,
.011759,-.009368,
.011939,-.008695,
.012,-.008,
.012,.008,
.011939,.008695,
.011759,.009368,
.011464,.01,
.011064,.010571,
.010571,.011064,
.01,.011464,
.009368,.011759,
.008695,.011939,
.008,.012,
-.008,.012,
-.008695,.011939,
-.009368,.011759,
-.01,.011464,
-.010571,.011064,
-.011064,.010571,
-.011464,.01,
-.011759,.009368,
-.011939,.008695,
-.012,.008,
-.012,-.008,
-.011939,-.008695,
-.011759,-.009368,
-.011464,-.01,
-.011064,-.010571,
-.010571,-.011064,
-.01,-.011464,
-.009368,-.011759,
-.008695,-.011939,
-.008,-.012,
0.0*
%
%ADD45MACRO45*%
%AMMACRO24*
4,1,40,.012,-.008,
.012,.008,
.011939,.008695,
.011759,.009368,
.011464,.01,
.011064,.010571,
.010571,.011064,
.01,.011464,
.009368,.011759,
.008695,.011939,
.008,.012,
-.008,.012,
-.008695,.011939,
-.009368,.011759,
-.01,.011464,
-.010571,.011064,
-.011064,.010571,
-.011464,.01,
-.011759,.009368,
-.011939,.008695,
-.012,.008,
-.012,-.008,
-.011939,-.008695,
-.011759,-.009368,
-.011464,-.01,
-.011064,-.010571,
-.010571,-.011064,
-.01,-.011464,
-.009368,-.011759,
-.008695,-.011939,
-.008,-.012,
.008,-.012,
.008695,-.011939,
.009368,-.011759,
.01,-.011464,
.010571,-.011064,
.011064,-.010571,
.011464,-.01,
.011759,-.009368,
.011939,-.008695,
.012,-.008,
0.0*
%
%ADD24MACRO24*%
%AMMACRO19*
4,1,40,-.007,-.011,
.007,-.011,
.007695,-.010939,
.008368,-.010759,
.009,-.010464,
.009571,-.010064,
.010064,-.009571,
.010464,-.009,
.010759,-.008368,
.010939,-.007695,
.011,-.007,
.011,.007,
.010939,.007695,
.010759,.008368,
.010464,.009,
.010064,.009571,
.009571,.010064,
.009,.010464,
.008368,.010759,
.007695,.010939,
.007,.011,
-.007,.011,
-.007695,.010939,
-.008368,.010759,
-.009,.010464,
-.009571,.010064,
-.010064,.009571,
-.010464,.009,
-.010759,.008368,
-.010939,.007695,
-.011,.007,
-.011,-.007,
-.010939,-.007695,
-.010759,-.008368,
-.010464,-.009,
-.010064,-.009571,
-.009571,-.010064,
-.009,-.010464,
-.008368,-.010759,
-.007695,-.010939,
-.007,-.011,
0.0*
%
%ADD19MACRO19*%
%AMMACRO11*
4,1,40,-.011,.007,
-.011,-.007,
-.010939,-.007695,
-.010759,-.008368,
-.010464,-.009,
-.010064,-.009571,
-.009571,-.010064,
-.009,-.010464,
-.008368,-.010759,
-.007695,-.010939,
-.007,-.011,
.007,-.011,
.007695,-.010939,
.008368,-.010759,
.009,-.010464,
.009571,-.010064,
.010064,-.009571,
.010464,-.009,
.010759,-.008368,
.010939,-.007695,
.011,-.007,
.011,.007,
.010939,.007695,
.010759,.008368,
.010464,.009,
.010064,.009571,
.009571,.010064,
.009,.010464,
.008368,.010759,
.007695,.010939,
.007,.011,
-.007,.011,
-.007695,.010939,
-.008368,.010759,
-.009,.010464,
-.009571,.010064,
-.010064,.009571,
-.010464,.009,
-.010759,.008368,
-.010939,.007695,
-.011,.007,
0.0*
%
%ADD11MACRO11*%
%ADD123C,.02*%
%ADD124C,.006*%
G75*
%LPD*%
G75*
G36*
G01X533408Y30785D02*
Y22235D01*
X542358D01*
Y30785D01*
X533408D01*
G37*
G36*
G01Y41935D02*
Y33385D01*
X542358D01*
Y41935D01*
X533408D01*
G37*
G36*
G01X544958Y30785D02*
Y22235D01*
X553908D01*
Y30785D01*
X544958D01*
G37*
G36*
G01Y41935D02*
Y33385D01*
X553908D01*
Y41935D01*
X544958D01*
G37*
G54D100*
X613087Y359016D03*
X615057D03*
X617027D03*
X618997D03*
Y349816D03*
X617027D03*
X615057D03*
X613087D03*
G54D101*
X625100Y494326D03*
Y510074D03*
G54D110*
X720039Y422909D03*
X704539D03*
G54D102*
X617350Y555400D03*
X721250Y576300D03*
G54D111*
X700546Y577599D03*
G54D120*
X818018Y260200D03*
X820218D03*
X818018Y262400D03*
X820218D03*
X818018Y255800D03*
X820218D03*
X818018Y253600D03*
X820218D03*
X818018Y266800D03*
X820218D03*
X818018Y269000D03*
X820218D03*
X818018Y273400D03*
X820218D03*
X818018Y275600D03*
X820218D03*
X818018Y280000D03*
X820218D03*
X818018Y282200D03*
X820218D03*
X818018Y286600D03*
X820218D03*
X818018Y288800D03*
X820218D03*
X818018Y293200D03*
X820218D03*
X818018Y295400D03*
X820218D03*
X818018Y299800D03*
X820218D03*
X818018Y302000D03*
X820218D03*
G54D10*
X38780Y48060D03*
X76100Y690300D03*
X89034Y55935D03*
X110220Y481998D03*
X142100Y519900D03*
X105920Y489718D03*
X110220Y489678D03*
X108600Y570550D03*
X123900Y648000D03*
X127900D03*
X140700Y650100D03*
X111200Y709900D03*
X80600Y685500D03*
X203500Y516900D03*
X199500Y517000D03*
X184167Y502984D03*
X183277Y485678D03*
X178920D03*
X151900Y633900D03*
X147800D03*
X168900Y633600D03*
X149400Y622800D03*
X193285Y621100D03*
X189185D03*
X185085D03*
X181085D03*
X177000Y620000D03*
X172900D03*
X164800Y633600D03*
X197555Y633257D03*
X200850Y643000D03*
X145300Y622800D03*
X208516Y653501D03*
X196648Y653621D03*
X161000Y644300D03*
X144800Y650100D03*
X164349Y695415D03*
X151749Y695715D03*
X166400Y704800D03*
X154300Y703515D03*
X216900Y512266D03*
X212600Y517000D03*
X225600Y515380D03*
X269600Y528100D03*
X252272Y613181D03*
X225900Y623700D03*
X229900Y625000D03*
X221900Y623700D03*
X238000Y622800D03*
X234000D03*
X223400Y638000D03*
X244156Y613787D03*
X242900Y675700D03*
X258431Y704490D03*
X249842Y707310D03*
X339851Y179517D03*
X340942Y528526D03*
X314181Y586050D03*
X297175Y535054D03*
X305100Y658100D03*
X289800Y660500D03*
X328000Y669900D03*
X291700Y730200D03*
X287620Y730220D03*
X370682Y192874D03*
X350000Y521000D03*
X354440Y485830D03*
X356680Y585664D03*
X374292Y583400D03*
X350000Y529000D03*
X385600Y532500D03*
X345900Y578100D03*
X392133Y594490D03*
X468200Y62600D03*
X463200Y55700D03*
X444754Y42401D03*
X472500Y62500D03*
X639067Y358591D03*
X613223Y372527D03*
X637147Y396797D03*
X646469Y417486D03*
X632628Y554627D03*
X727150Y187850D03*
X722150D03*
X725678Y176992D03*
X711150Y177600D03*
X716650Y187850D03*
X705650D03*
X711150D03*
X714090Y324840D03*
X706000Y324800D03*
X727200Y356100D03*
X722500Y346300D03*
X713500Y356200D03*
X718000Y346300D03*
X689000Y499800D03*
X713575Y552777D03*
X728000Y580250D03*
X703800Y601500D03*
X784161Y123415D03*
X784400Y99300D03*
X741300Y188800D03*
X758100Y188400D03*
X754000Y188800D03*
X738365Y356035D03*
X790400Y416400D03*
X795922Y522908D03*
X777200Y496800D03*
X759200Y500800D03*
X753099Y523066D03*
X748899Y522966D03*
X818688Y403255D03*
X857000Y403400D03*
X805249Y519877D03*
X885568Y318641D03*
G54D121*
X892449Y237028D03*
Y230972D03*
X888551Y237028D03*
Y230972D03*
G54D112*
X710389Y567956D03*
X708420D03*
X706452D03*
X704483D03*
X702515D03*
X700546D03*
X698577D03*
X696609D03*
X694640D03*
X692672D03*
X690703D03*
Y587242D03*
X692672D03*
X694640D03*
X696609D03*
X698577D03*
X700546D03*
X702515D03*
X704483D03*
X706452D03*
X708420D03*
X710389D03*
G54D103*
X614650Y555400D03*
X718550Y576300D03*
G54D11*
X38780Y51460D03*
X76100Y693700D03*
X89034Y59335D03*
X110220Y485398D03*
X142100Y523300D03*
X105920Y493118D03*
X110220Y493078D03*
X108600Y573950D03*
X123900Y651400D03*
X127900D03*
X140700Y653500D03*
X111200Y713300D03*
X80600Y688900D03*
X203500Y520300D03*
X199500Y520400D03*
X184167Y506384D03*
X183277Y489078D03*
X178920D03*
X151900Y637300D03*
X147800D03*
X168900Y637000D03*
X149400Y626200D03*
X193285Y624500D03*
X189185D03*
X185085D03*
X181085D03*
X177000Y623400D03*
X172900D03*
X164800Y637000D03*
X197555Y636657D03*
X200850Y646400D03*
X145300Y626200D03*
X208516Y656901D03*
X196648Y657021D03*
X161000Y647700D03*
X144800Y653500D03*
X164349Y698815D03*
X151749Y699115D03*
X166400Y708200D03*
X154300Y706915D03*
X216900Y515666D03*
X212600Y520400D03*
X225600Y518780D03*
X269600Y531500D03*
X252272Y616581D03*
X225900Y627100D03*
X229900Y628400D03*
X221900Y627100D03*
X238000Y626200D03*
X234000D03*
X223400Y641400D03*
X244156Y617187D03*
X242900Y679100D03*
X258431Y707890D03*
X249842Y710710D03*
X339851Y182917D03*
X340942Y531926D03*
X314181Y589450D03*
X297175Y538454D03*
X305100Y661500D03*
X289800Y663900D03*
X328000Y673300D03*
X291700Y733600D03*
X287620Y733620D03*
X370682Y196274D03*
X350000Y524400D03*
X354440Y489230D03*
X356680Y589064D03*
X374292Y586800D03*
X350000Y532400D03*
X385600Y535900D03*
X345900Y581500D03*
X392133Y597890D03*
X468200Y66000D03*
X463200Y59100D03*
X444754Y45801D03*
X472500Y65900D03*
X639067Y361991D03*
X613223Y375927D03*
X646469Y420886D03*
X637147Y400197D03*
X632628Y558027D03*
X727150Y191250D03*
X722150D03*
X725678Y180392D03*
X711150Y181000D03*
X716650Y191250D03*
X705650D03*
X711150D03*
X714090Y328240D03*
X706000Y328200D03*
X727200Y359500D03*
X722500Y349700D03*
X713500Y359600D03*
X718000Y349700D03*
X689000Y503200D03*
X713575Y556177D03*
X728000Y583650D03*
X703800Y604900D03*
X784161Y126815D03*
X784400Y102700D03*
X741300Y192200D03*
X758100Y191800D03*
X754000Y192200D03*
X738365Y359435D03*
X790400Y419800D03*
X795922Y526308D03*
X777200Y500200D03*
X759200Y504200D03*
X753099Y526466D03*
X748899Y526366D03*
X818688Y406655D03*
X857000Y406800D03*
X805249Y523277D03*
X885568Y322041D03*
G54D122*
X893634Y364633D03*
Y397685D03*
G54D113*
X679800Y634661D03*
Y599739D03*
G54D20*
X33265Y532638D03*
X61454Y639950D03*
X38733Y679946D03*
X131262Y603311D03*
X132018Y617677D03*
X131250Y599250D03*
X132753Y609777D03*
X109300Y597000D03*
Y601000D03*
Y609000D03*
Y605000D03*
Y613000D03*
X109800Y621000D03*
X109300Y617000D03*
X109899Y701465D03*
X137649Y687715D03*
X179544Y459767D03*
Y469867D03*
X174341Y495710D03*
X200200Y495600D03*
X208700Y499300D03*
X268000Y458200D03*
X268400Y490300D03*
X268000Y470300D03*
X239900Y581100D03*
X239570Y556658D03*
X263841Y543759D03*
X262900Y567300D03*
X266800Y572100D03*
X239618Y568821D03*
Y572821D03*
X240000Y576900D03*
X242293Y532802D03*
X273367Y557480D03*
X256220Y532870D03*
X267600Y605500D03*
X232900Y637600D03*
X266600Y643000D03*
X258300D03*
X259696Y630071D03*
X275450Y602700D03*
X267200Y723500D03*
X340247Y226992D03*
X340282Y256474D03*
X327121Y526309D03*
X291455Y546906D03*
X291500Y551300D03*
X326780Y531380D03*
X332465Y539609D03*
X326316Y543816D03*
X305051Y535356D03*
X287600Y617000D03*
X302000Y616384D03*
X291318Y684153D03*
X345631Y242261D03*
X345722Y247314D03*
X342794Y268585D03*
X343091Y272906D03*
X347800Y511900D03*
Y503600D03*
X387600Y589571D03*
X386579Y585543D03*
X386300Y576500D03*
Y572500D03*
X387700Y602100D03*
X387736Y619701D03*
X387700Y606200D03*
X387586Y628081D03*
X387550Y637348D03*
X385225Y693371D03*
X385700Y671800D03*
X388655Y684644D03*
X386200Y677900D03*
X434185Y38057D03*
X442616Y38147D03*
X437081Y56947D03*
X442685Y30457D03*
Y26157D03*
X442585Y21957D03*
X489800Y30000D03*
Y22000D03*
Y26000D03*
X525500Y49400D03*
Y53600D03*
X559300Y82000D03*
X630322Y379591D03*
X662200Y443200D03*
X639500Y553700D03*
X681642Y244547D03*
X694900Y249400D03*
X696100Y207600D03*
X720200Y564600D03*
Y560600D03*
X716176Y598329D03*
X767734Y518500D03*
X740100Y501300D03*
X811800Y322500D03*
X814572Y393639D03*
X814867Y398968D03*
X805900Y473500D03*
G54D104*
X627160Y538043D03*
G54D123*
G01X-13131Y-65072D02*
Y-145072D01*
G01D02*
X1244069D01*
G01X-29131Y-65072D02*
Y-33072D01*
G01X-13131Y-65072D02*
X1244069D01*
G01X-13131Y-100572D02*
X1244069D01*
G01X-17131Y-49072D02*
G02I-12000J0D01*
G01X-22281D02*
G02I-6850J0D01*
G01X-13131D02*
X-45131D01*
G01X456569Y-65072D02*
Y-145072D01*
G01X594069Y-65072D02*
Y-145072D01*
G01X709069Y-65072D02*
Y-145072D01*
G01X876569Y-65072D02*
Y-145072D01*
G01X1046569Y-65072D02*
Y-145072D01*
G01X1244069Y-65072D02*
Y-145072D01*
G01X1272069Y-49072D02*
G02I-12000J0D01*
G01X1266919D02*
G02I-6850J0D01*
G01X1276069D02*
X1244069D01*
G01X1260069Y-65072D02*
Y-33072D01*
G54D105*
X633266Y540996D03*
Y535090D03*
X621054D03*
Y540996D03*
G54D30*
X49900Y674984D03*
X117700Y518800D03*
X85500Y636300D03*
X81784Y671500D03*
X203650Y636650D03*
X207060Y633220D03*
X170100Y708200D03*
X210520Y632910D03*
X247400Y643000D03*
X225400Y716600D03*
X263000Y679300D03*
X328659Y539659D03*
X317600Y610400D03*
X322100Y645300D03*
X314920Y682520D03*
X311704Y715720D03*
X366699Y204821D03*
X521800Y53400D03*
X559200Y44100D03*
X633800Y341500D03*
X614000Y340900D03*
X645300Y529800D03*
X702460Y484650D03*
X728559Y477898D03*
X676194Y589729D03*
X723676Y591229D03*
X776200Y54800D03*
X786600Y419800D03*
X794500Y501200D03*
X757099Y526566D03*
X826284Y505500D03*
X883100Y224700D03*
G54D21*
X36665Y532638D03*
X64854Y639950D03*
X42133Y679946D03*
X134662Y603311D03*
X135418Y617677D03*
X134650Y599250D03*
X136153Y609777D03*
X112700Y597000D03*
Y601000D03*
Y609000D03*
Y605000D03*
Y613000D03*
X113200Y621000D03*
X112700Y617000D03*
X113299Y701465D03*
X141049Y687715D03*
X182944Y459767D03*
Y469867D03*
X177741Y495710D03*
X203600Y495600D03*
X271400Y458200D03*
X271800Y490300D03*
X271400Y470300D03*
X212100Y499300D03*
X243300Y581100D03*
X242970Y556658D03*
X267241Y543759D03*
X266300Y567300D03*
X270200Y572100D03*
X243018Y568821D03*
Y572821D03*
X243400Y576900D03*
X245693Y532802D03*
X259620Y532870D03*
X271000Y605500D03*
X236300Y637600D03*
X270000Y643000D03*
X261700D03*
X263096Y630071D03*
X270600Y723500D03*
X330521Y526309D03*
X294855Y546906D03*
X294900Y551300D03*
X276767Y557480D03*
X330180Y531380D03*
X335865Y539609D03*
X329716Y543816D03*
X308451Y535356D03*
X291000Y617000D03*
X305400Y616384D03*
X278850Y602700D03*
X294718Y684153D03*
X343647Y226992D03*
X349031Y242261D03*
X349122Y247314D03*
X343682Y256474D03*
X346194Y268585D03*
X346491Y272906D03*
X351200Y511900D03*
Y503600D03*
X391000Y589571D03*
X389979Y585543D03*
X389700Y576500D03*
Y572500D03*
X391100Y602100D03*
X391136Y619701D03*
X391100Y606200D03*
X390986Y628081D03*
X390950Y637348D03*
X388625Y693371D03*
X389100Y671800D03*
X392055Y684644D03*
X389600Y677900D03*
X437585Y38057D03*
X446016Y38147D03*
X440481Y56947D03*
X446085Y30457D03*
Y26157D03*
X445985Y21957D03*
X493200Y30000D03*
Y22000D03*
Y26000D03*
X528900Y49400D03*
Y53600D03*
X562700Y82000D03*
X633722Y379591D03*
X665600Y443200D03*
X642900Y553700D03*
X685042Y244547D03*
X698300Y249400D03*
X699500Y207600D03*
X723600Y564600D03*
Y560600D03*
X719576Y598329D03*
X771134Y518500D03*
X743500Y501300D03*
X815200Y322500D03*
X817972Y393639D03*
X818267Y398968D03*
X809300Y473500D03*
G54D12*
X58010Y52510D03*
X75373Y509879D03*
X75405Y517477D03*
X69900Y510000D03*
X69778Y517477D03*
X46100Y674984D03*
X79570Y58460D03*
X81032Y517477D03*
X81068Y509866D03*
X105920Y485398D03*
X86659Y517477D03*
X86673Y510000D03*
X92000Y517400D03*
X101100Y515300D03*
X101113Y522777D03*
X142000Y515500D03*
X93531Y496341D03*
X132100Y651400D03*
X136100D03*
X113349Y697047D03*
X117449D03*
X121549Y694747D03*
X193000Y506400D03*
X146112Y516498D03*
X183320Y481498D03*
X178920D03*
X174715Y520420D03*
X187000Y520400D03*
X191100Y519900D03*
X170700Y520400D03*
X166600D03*
X178869Y520393D03*
X182874Y520391D03*
X160727Y520222D03*
X150112Y516498D03*
X156721Y520192D03*
X188400Y506300D03*
X185276Y636268D03*
X177100Y637000D03*
X173000D03*
X202560Y627466D03*
X197315Y625797D03*
X153700Y626200D03*
X189376Y636268D03*
X193476D03*
X181146Y637008D03*
X188400Y647400D03*
X149300Y648400D03*
X204357Y656886D03*
X191746Y657042D03*
X165000Y647700D03*
X155849Y699115D03*
X158349Y706915D03*
X230262Y518680D03*
X234348Y518614D03*
X238648D03*
X242700Y518620D03*
X243400Y642900D03*
X248215Y616587D03*
X219200Y644000D03*
X231300Y645500D03*
X211706Y641392D03*
X251900Y679700D03*
X238936Y666869D03*
X258500Y679200D03*
X266800Y671000D03*
X262645Y707901D03*
X270900Y674000D03*
X293150Y538700D03*
X289050D03*
X300200Y593600D03*
X304300D03*
X336500Y673500D03*
X391262Y72271D03*
X386027Y72240D03*
X362484Y200119D03*
X349004Y183030D03*
X363553Y479662D03*
X382550Y584806D03*
X360820Y590236D03*
X352480Y589564D03*
X378350Y584806D03*
X345287Y540959D03*
X391549Y563600D03*
X387733Y597990D03*
X348600Y639000D03*
X444722Y53415D03*
X603164Y544203D03*
X639040Y161110D03*
X634661Y370756D03*
X620822Y375864D03*
X623239Y340879D03*
X608500Y339400D03*
X640160Y525243D03*
X619400Y567200D03*
X623542Y567152D03*
X732000Y192400D03*
X734028Y182346D03*
X716650Y181000D03*
X710060Y328260D03*
X727000Y349700D03*
X731400Y359400D03*
X711700Y348700D03*
X696527Y460706D03*
X696700Y473300D03*
X702390Y492260D03*
X731676Y591129D03*
X707826Y604879D03*
X716345Y611790D03*
X777700Y77600D03*
X795600Y191800D03*
X790600D03*
X762200Y192200D03*
X745700Y192400D03*
X737000D03*
X775500Y191700D03*
X749900Y192100D03*
X785600Y191800D03*
X738465Y349635D03*
X777000Y492500D03*
X751400Y504200D03*
X777084Y526450D03*
X841300Y61280D03*
X809349Y70036D03*
X813449D03*
X805600Y191800D03*
X800600D03*
X810600D03*
X857569Y388333D03*
X861000Y406800D03*
X882913Y232198D03*
G54D114*
X761800Y438310D03*
Y461858D03*
G54D124*
G01X13215Y-125739D02*
X14089Y-124864D01*
X14744Y-123406D01*
X15181Y-121363D01*
X14744Y-119614D01*
X13871Y-118447D01*
X12342Y-117572D01*
X6447D01*
Y-135072D01*
X13652D01*
X15181Y-133906D01*
X16054Y-132155D01*
X16491Y-130114D01*
X16054Y-128072D01*
X14744Y-126322D01*
X13215Y-125739D01*
X6447D01*
G01X25912Y-135072D02*
Y-123406D01*
G01Y-125739D02*
X27004Y-124572D01*
X28096Y-123697D01*
X29624Y-123406D01*
X30715Y-123697D01*
X32026Y-124572D01*
G01X41884Y-140322D02*
X43194Y-140905D01*
X44941Y-140322D01*
X46032Y-139156D01*
X46906Y-137697D01*
X48215Y-133031D01*
X51054Y-123406D01*
G01X44067D02*
X48215Y-133031D01*
G01X67462Y-124864D02*
X65934Y-123697D01*
X64624Y-123406D01*
X62877Y-123989D01*
X61567Y-125155D01*
X60694Y-127197D01*
X60475Y-129239D01*
X60694Y-131281D01*
X61567Y-133031D01*
X62877Y-134489D01*
X64624Y-135072D01*
X66152Y-134489D01*
X67462Y-133322D01*
G01X78194Y-127197D02*
X85181D01*
X84526Y-125155D01*
X83434Y-123989D01*
X81906Y-123406D01*
X80377Y-123697D01*
X79067Y-124572D01*
X78194Y-126614D01*
X77757Y-128364D01*
Y-130114D01*
X78194Y-131864D01*
X79286Y-133614D01*
X80596Y-134780D01*
X82124Y-135072D01*
X83652Y-134489D01*
X85181Y-132739D01*
G01X121272Y-119031D02*
X119962Y-118155D01*
X118434Y-117572D01*
X116687D01*
X114722Y-118447D01*
X113194Y-119905D01*
X112102Y-121656D01*
X111229Y-124572D01*
X111010Y-127197D01*
X111447Y-129822D01*
X112102Y-131572D01*
X113412Y-133322D01*
X114941Y-134489D01*
X116469Y-135072D01*
X117997D01*
X119526Y-134489D01*
X120836Y-133614D01*
X121928Y-132448D01*
G01X137899Y-135072D02*
Y-123406D01*
G01Y-125447D02*
X137026Y-124281D01*
X135715Y-123697D01*
X134187Y-123406D01*
X132659Y-123989D01*
X131349Y-125155D01*
X130475Y-126905D01*
X130039Y-129239D01*
X130475Y-131572D01*
X131349Y-133322D01*
X132659Y-134489D01*
X134187Y-135072D01*
X135715Y-134780D01*
X137026Y-133906D01*
X137899Y-132739D01*
G01X147757Y-135072D02*
Y-123406D01*
G01Y-126322D02*
X148631Y-124864D01*
X149941Y-123697D01*
X151687Y-123406D01*
X153215Y-123697D01*
X154526Y-124864D01*
X155181Y-126905D01*
Y-135072D01*
G01X164384Y-140322D02*
X165694Y-140905D01*
X167441Y-140322D01*
X168532Y-139156D01*
X169406Y-137697D01*
X170715Y-133031D01*
X173554Y-123406D01*
G01X166567D02*
X170715Y-133031D01*
G01X186469Y-135072D02*
X185159Y-134780D01*
X183849Y-133614D01*
X182975Y-131572D01*
X182539Y-129239D01*
X182975Y-126905D01*
X183849Y-124864D01*
X185159Y-123697D01*
X186469Y-123406D01*
X187779Y-123697D01*
X189089Y-124864D01*
X189962Y-126905D01*
X190181Y-129239D01*
X189962Y-131572D01*
X189089Y-133614D01*
X187779Y-134780D01*
X186469Y-135072D01*
G01X200257D02*
Y-123406D01*
G01Y-126322D02*
X201131Y-124864D01*
X202441Y-123697D01*
X204187Y-123406D01*
X205715Y-123697D01*
X207026Y-124864D01*
X207681Y-126905D01*
Y-135072D01*
G01X236349Y-117572D02*
X241589D01*
G01X238969D02*
Y-135072D01*
G01X236349D02*
X241589D01*
G01X256469D02*
X254722Y-134780D01*
X253194Y-133614D01*
X251884Y-131864D01*
X251010Y-129822D01*
X250574Y-127489D01*
Y-125155D01*
X251010Y-122822D01*
X251884Y-120780D01*
X253194Y-119031D01*
X254722Y-117864D01*
X256469Y-117572D01*
X258215Y-117864D01*
X259744Y-119031D01*
X261054Y-120780D01*
X261928Y-122822D01*
X262364Y-125155D01*
Y-127489D01*
X261928Y-129822D01*
X261054Y-131864D01*
X259744Y-133614D01*
X258215Y-134780D01*
X256469Y-135072D01*
G01X268292D02*
Y-117572D01*
X273969Y-132155D01*
X279646Y-117572D01*
Y-135072D01*
G01X307877Y-140905D02*
X305694Y-137989D01*
X304602Y-135072D01*
Y-123406D01*
X305694Y-120489D01*
X307877Y-117572D01*
G01X321010Y-123406D02*
X323631Y-135072D01*
X326469Y-123406D01*
X329307Y-135072D01*
X331928Y-123406D01*
G01X340039Y-135655D02*
X347899Y-117572D01*
G01X376349D02*
X381589D01*
G01X378969D02*
Y-135072D01*
G01X376349D02*
X381589D01*
G01X396469D02*
X394722Y-134780D01*
X393194Y-133614D01*
X391884Y-131864D01*
X391010Y-129822D01*
X390574Y-127489D01*
Y-125155D01*
X391010Y-122822D01*
X391884Y-120780D01*
X393194Y-119031D01*
X394722Y-117864D01*
X396469Y-117572D01*
X398215Y-117864D01*
X399744Y-119031D01*
X401054Y-120780D01*
X401928Y-122822D01*
X402364Y-125155D01*
Y-127489D01*
X401928Y-129822D01*
X401054Y-131864D01*
X399744Y-133614D01*
X398215Y-134780D01*
X396469Y-135072D01*
G01X418772Y-119031D02*
X417462Y-118155D01*
X415934Y-117572D01*
X414187D01*
X412222Y-118447D01*
X410694Y-119905D01*
X409602Y-121656D01*
X408729Y-124572D01*
X408510Y-127197D01*
X408947Y-129822D01*
X409602Y-131572D01*
X410912Y-133322D01*
X412441Y-134489D01*
X413969Y-135072D01*
X415497D01*
X417026Y-134489D01*
X418336Y-133614D01*
X419428Y-132448D01*
G01X432561Y-140905D02*
X434744Y-137989D01*
X435836Y-135072D01*
Y-123406D01*
X434744Y-120489D01*
X432561Y-117572D01*
G01X180792Y-90072D02*
Y-72572D01*
X186469Y-87155D01*
X192146Y-72572D01*
Y-90072D01*
G01X203969D02*
X202659Y-89780D01*
X201349Y-88614D01*
X200475Y-86572D01*
X200039Y-84239D01*
X200475Y-81905D01*
X201349Y-79864D01*
X202659Y-78697D01*
X203969Y-78406D01*
X205279Y-78697D01*
X206589Y-79864D01*
X207462Y-81905D01*
X207681Y-84239D01*
X207462Y-86572D01*
X206589Y-88614D01*
X205279Y-89780D01*
X203969Y-90072D01*
G01X225399Y-72572D02*
Y-90072D01*
G01Y-87448D02*
X224526Y-88906D01*
X223215Y-89780D01*
X221687Y-90072D01*
X219941Y-89489D01*
X218631Y-88031D01*
X217757Y-86281D01*
X217539Y-84239D01*
X217757Y-82197D01*
X218631Y-80447D01*
X219941Y-78989D01*
X221687Y-78406D01*
X223215Y-78697D01*
X224307Y-79281D01*
X225399Y-80447D01*
G01X235694Y-82197D02*
X242681D01*
X242026Y-80155D01*
X240934Y-78989D01*
X239406Y-78406D01*
X237877Y-78697D01*
X236567Y-79572D01*
X235694Y-81614D01*
X235257Y-83364D01*
Y-85114D01*
X235694Y-86864D01*
X236786Y-88614D01*
X238096Y-89780D01*
X239624Y-90072D01*
X241152Y-89489D01*
X242681Y-87739D01*
G01X256469Y-90072D02*
Y-72572D01*
G01X490269Y-135072D02*
Y-117572D01*
X487649Y-121072D01*
G01Y-135072D02*
X492889D01*
G01X503621Y-127781D02*
X505149Y-125739D01*
X506459Y-124572D01*
X508206Y-123989D01*
X509734Y-124572D01*
X510826Y-125739D01*
X511699Y-127489D01*
X511917Y-129530D01*
X511699Y-131281D01*
X510826Y-133031D01*
X509515Y-134489D01*
X507987Y-135072D01*
X506241Y-134489D01*
X504712Y-132739D01*
X503839Y-130114D01*
X503621Y-127197D01*
X504057Y-123406D01*
X504712Y-121363D01*
X505804Y-119322D01*
X507332Y-117864D01*
X508861Y-117572D01*
X510389Y-118155D01*
X511481Y-119614D01*
G01X520466Y-131572D02*
X521775Y-133614D01*
X523522Y-134780D01*
X525487Y-135072D01*
X527234Y-134780D01*
X528981Y-133322D01*
X530072Y-131572D01*
X530291Y-129822D01*
X529854Y-127781D01*
X528326Y-126322D01*
X526797Y-125739D01*
X524832D01*
G01X526797D02*
X528107Y-124864D01*
X529199Y-123406D01*
X529636Y-121656D01*
X529199Y-119905D01*
X528107Y-118447D01*
X526142Y-117572D01*
X524177Y-117864D01*
X522212Y-119031D01*
G01X542769Y-135072D02*
Y-117572D01*
X540149Y-121072D01*
G01Y-135072D02*
X545389D01*
G01X560269D02*
X561797Y-134780D01*
X563544Y-133906D01*
X564636Y-132448D01*
X565072Y-130405D01*
X564636Y-128364D01*
X563326Y-126614D01*
X561361Y-125739D01*
X559177D01*
X557867Y-125155D01*
X556775Y-123697D01*
X556339Y-121656D01*
X556994Y-119614D01*
X558522Y-118155D01*
X560269Y-117572D01*
X562015Y-118155D01*
X563544Y-119614D01*
X564199Y-121656D01*
X563762Y-123697D01*
X562671Y-125155D01*
X561361Y-125739D01*
X559177D01*
X557212Y-126614D01*
X555902Y-128364D01*
X555466Y-130405D01*
X555902Y-132448D01*
X556994Y-133906D01*
X558741Y-134780D01*
X560269Y-135072D01*
G01X477152Y-90072D02*
Y-72572D01*
X482392D01*
X484139Y-73447D01*
X485449Y-75489D01*
X485886Y-77822D01*
X485449Y-80155D01*
X484357Y-81905D01*
X482392Y-82781D01*
X477152D01*
G01X503822Y-74031D02*
X502512Y-73155D01*
X500984Y-72572D01*
X499237D01*
X497272Y-73447D01*
X495744Y-74905D01*
X494652Y-76656D01*
X493779Y-79572D01*
X493560Y-82197D01*
X493997Y-84822D01*
X494652Y-86572D01*
X495962Y-88322D01*
X497491Y-89489D01*
X499019Y-90072D01*
X500547D01*
X502076Y-89489D01*
X503386Y-88614D01*
X504478Y-87448D01*
G01X518265Y-80739D02*
X519139Y-79864D01*
X519794Y-78406D01*
X520231Y-76363D01*
X519794Y-74614D01*
X518921Y-73447D01*
X517392Y-72572D01*
X511497D01*
Y-90072D01*
X518702D01*
X520231Y-88906D01*
X521104Y-87155D01*
X521541Y-85114D01*
X521104Y-83072D01*
X519794Y-81322D01*
X518265Y-80739D01*
X511497D01*
G01X527469Y-95905D02*
X540569D01*
G01X546497Y-90072D02*
Y-72572D01*
X556541Y-90072D01*
Y-72572D01*
G01X569019Y-90072D02*
X567272Y-89780D01*
X565744Y-88614D01*
X564434Y-86864D01*
X563560Y-84822D01*
X563124Y-82489D01*
Y-80155D01*
X563560Y-77822D01*
X564434Y-75780D01*
X565744Y-74031D01*
X567272Y-72864D01*
X569019Y-72572D01*
X570765Y-72864D01*
X572294Y-74031D01*
X573604Y-75780D01*
X574478Y-77822D01*
X574914Y-80155D01*
Y-82489D01*
X574478Y-84822D01*
X573604Y-86864D01*
X572294Y-88614D01*
X570765Y-89780D01*
X569019Y-90072D01*
G01X647421Y-120489D02*
X648731Y-118739D01*
X650259Y-117864D01*
X652006Y-117572D01*
X654189Y-118155D01*
X655717Y-119614D01*
X656154Y-121363D01*
X655936Y-123114D01*
X655062Y-124572D01*
X650696Y-127489D01*
X648731Y-129530D01*
X647421Y-132448D01*
X646984Y-135072D01*
X656154D01*
G01X619860Y-72572D02*
X625319Y-90072D01*
X630778Y-72572D01*
G01X647186Y-90072D02*
X638452D01*
Y-72572D01*
X647186D01*
G01X643692Y-81030D02*
X638452D01*
G01X655952Y-90072D02*
Y-72572D01*
X661411D01*
X663157Y-73447D01*
X664249Y-74614D01*
X664686Y-76947D01*
X664249Y-79281D01*
X662939Y-80739D01*
X661411Y-81614D01*
X655952D01*
G01X661411D02*
X664686Y-90072D01*
G01X677819Y-90655D02*
X677382Y-90364D01*
Y-89780D01*
X677819Y-89489D01*
X678256Y-89780D01*
Y-90364D01*
X677819Y-90655D01*
G01X766519Y-117572D02*
Y-135072D01*
G01X761497Y-117572D02*
X771541D01*
G01X779434Y-132739D02*
X781181Y-134197D01*
X783146Y-135072D01*
X784892D01*
X786639Y-134197D01*
X787949Y-132739D01*
X788604Y-130697D01*
X788167Y-128656D01*
X787076Y-126905D01*
X785111Y-125739D01*
X782491Y-125155D01*
X780962Y-123989D01*
X780307Y-121947D01*
X780744Y-119905D01*
X781836Y-118447D01*
X783364Y-117572D01*
X784892D01*
X786421Y-118155D01*
X787731Y-119614D01*
G01X795842Y-135072D02*
Y-117572D01*
X801519Y-132155D01*
X807196Y-117572D01*
Y-135072D01*
G01X814216D02*
Y-117572D01*
X818582D01*
X820329Y-118447D01*
X821639Y-119614D01*
X822731Y-121363D01*
X823604Y-123406D01*
X823822Y-126322D01*
X823604Y-129239D01*
X822731Y-131281D01*
X821639Y-133031D01*
X820329Y-134197D01*
X818582Y-135072D01*
X814216D01*
G01X753402Y-72572D02*
Y-90072D01*
X762136D01*
G01X779199D02*
Y-78406D01*
G01Y-80447D02*
X778326Y-79281D01*
X777015Y-78697D01*
X775487Y-78406D01*
X773959Y-78989D01*
X772649Y-80155D01*
X771775Y-81905D01*
X771339Y-84239D01*
X771775Y-86572D01*
X772649Y-88322D01*
X773959Y-89489D01*
X775487Y-90072D01*
X777015Y-89780D01*
X778326Y-88906D01*
X779199Y-87739D01*
G01X788184Y-95322D02*
X789494Y-95905D01*
X791241Y-95322D01*
X792332Y-94156D01*
X793206Y-92697D01*
X794515Y-88031D01*
X797354Y-78406D01*
G01X790367D02*
X794515Y-88031D01*
G01X806994Y-82197D02*
X813981D01*
X813326Y-80155D01*
X812234Y-78989D01*
X810706Y-78406D01*
X809177Y-78697D01*
X807867Y-79572D01*
X806994Y-81614D01*
X806557Y-83364D01*
Y-85114D01*
X806994Y-86864D01*
X808086Y-88614D01*
X809396Y-89780D01*
X810924Y-90072D01*
X812452Y-89489D01*
X813981Y-87739D01*
G01X824712Y-90072D02*
Y-78406D01*
G01Y-80739D02*
X825804Y-79572D01*
X826896Y-78697D01*
X828424Y-78406D01*
X829515Y-78697D01*
X830826Y-79572D01*
G01X917819Y-135072D02*
X916072Y-134780D01*
X914544Y-133614D01*
X913234Y-131864D01*
X912360Y-129822D01*
X911924Y-127489D01*
Y-125155D01*
X912360Y-122822D01*
X913234Y-120780D01*
X914544Y-119031D01*
X916072Y-117864D01*
X917819Y-117572D01*
X919565Y-117864D01*
X921094Y-119031D01*
X922404Y-120780D01*
X923278Y-122822D01*
X923714Y-125155D01*
Y-127489D01*
X923278Y-129822D01*
X922404Y-131864D01*
X921094Y-133614D01*
X919565Y-134780D01*
X917819Y-135072D01*
G01X919565Y-130405D02*
X922186Y-135072D01*
G01X930516Y-117572D02*
Y-130114D01*
X931389Y-132739D01*
X933136Y-134489D01*
X935319Y-135072D01*
X937502Y-134489D01*
X939249Y-132739D01*
X940122Y-130114D01*
Y-117572D01*
G01X950199D02*
X955439D01*
G01X952819D02*
Y-135072D01*
G01X950199D02*
X955439D01*
G01X965297D02*
Y-117572D01*
X975341Y-135072D01*
Y-117572D01*
G01X992622Y-119031D02*
X991312Y-118155D01*
X989784Y-117572D01*
X988037D01*
X986072Y-118447D01*
X984544Y-119905D01*
X983452Y-121656D01*
X982579Y-124572D01*
X982360Y-127197D01*
X982797Y-129822D01*
X983452Y-131572D01*
X984762Y-133322D01*
X986291Y-134489D01*
X987819Y-135072D01*
X989347D01*
X990876Y-134489D01*
X992186Y-133614D01*
X993278Y-132448D01*
G01X1005319Y-135072D02*
Y-127197D01*
X1000952Y-117572D01*
G01X1009686D02*
X1005319Y-127197D01*
G01X895516Y-90072D02*
Y-72572D01*
X899882D01*
X901629Y-73447D01*
X902939Y-74614D01*
X904031Y-76363D01*
X904904Y-78406D01*
X905122Y-81322D01*
X904904Y-84239D01*
X904031Y-86281D01*
X902939Y-88031D01*
X901629Y-89197D01*
X899882Y-90072D01*
X895516D01*
G01X914544Y-82197D02*
X921531D01*
X920876Y-80155D01*
X919784Y-78989D01*
X918256Y-78406D01*
X916727Y-78697D01*
X915417Y-79572D01*
X914544Y-81614D01*
X914107Y-83364D01*
Y-85114D01*
X914544Y-86864D01*
X915636Y-88614D01*
X916946Y-89780D01*
X918474Y-90072D01*
X920002Y-89489D01*
X921531Y-87739D01*
G01X932044Y-88031D02*
X933136Y-89197D01*
X934664Y-90072D01*
X935974D01*
X937284Y-89489D01*
X938157Y-88614D01*
X938594Y-87448D01*
X938376Y-85697D01*
X937502Y-84822D01*
X933572Y-83072D01*
X932699Y-81030D01*
X933136Y-79572D01*
X934009Y-78697D01*
X935319Y-78406D01*
X936629Y-78697D01*
X937939Y-79572D01*
G01X952819Y-78406D02*
Y-90072D01*
G01Y-73739D02*
X952382Y-73447D01*
Y-72864D01*
X952819Y-72572D01*
X953256Y-72864D01*
Y-73447D01*
X952819Y-73739D01*
G01X967262Y-94447D02*
X968791Y-95614D01*
X970537Y-95905D01*
X972065Y-95614D01*
X973376Y-94156D01*
X974249Y-92114D01*
Y-78406D01*
G01Y-80739D02*
X973376Y-79572D01*
X972065Y-78697D01*
X970537Y-78406D01*
X968791Y-78989D01*
X967699Y-80155D01*
X966825Y-82197D01*
X966389Y-84239D01*
X966607Y-85989D01*
X967481Y-88031D01*
X968791Y-89489D01*
X970537Y-90072D01*
X971847Y-89780D01*
X973376Y-88614D01*
X974249Y-87448D01*
G01X984107Y-90072D02*
Y-78406D01*
G01Y-81322D02*
X984981Y-79864D01*
X986291Y-78697D01*
X988037Y-78406D01*
X989565Y-78697D01*
X990876Y-79864D01*
X991531Y-81905D01*
Y-90072D01*
G01X1002044Y-82197D02*
X1009031D01*
X1008376Y-80155D01*
X1007284Y-78989D01*
X1005756Y-78406D01*
X1004227Y-78697D01*
X1002917Y-79572D01*
X1002044Y-81614D01*
X1001607Y-83364D01*
Y-85114D01*
X1002044Y-86864D01*
X1003136Y-88614D01*
X1004446Y-89780D01*
X1005974Y-90072D01*
X1007502Y-89489D01*
X1009031Y-87739D01*
G01X1019762Y-90072D02*
Y-78406D01*
G01Y-80739D02*
X1020854Y-79572D01*
X1021946Y-78697D01*
X1023474Y-78406D01*
X1024565Y-78697D01*
X1025876Y-79572D01*
G01X1066519Y-117572D02*
X1064772Y-118155D01*
X1063462Y-119614D01*
X1062589Y-121363D01*
X1061934Y-123697D01*
X1061716Y-126322D01*
X1061934Y-128947D01*
X1062589Y-131281D01*
X1063462Y-133031D01*
X1064772Y-134489D01*
X1066519Y-135072D01*
X1068265Y-134489D01*
X1069576Y-133031D01*
X1070449Y-131281D01*
X1071104Y-128947D01*
X1071322Y-126322D01*
X1071104Y-123697D01*
X1070449Y-121363D01*
X1069576Y-119614D01*
X1068265Y-118155D01*
X1066519Y-117572D01*
G01X1084019Y-135072D02*
X1085547Y-134780D01*
X1087294Y-133906D01*
X1088386Y-132448D01*
X1088822Y-130405D01*
X1088386Y-128364D01*
X1087076Y-126614D01*
X1085111Y-125739D01*
X1082927D01*
X1081617Y-125155D01*
X1080525Y-123697D01*
X1080089Y-121656D01*
X1080744Y-119614D01*
X1082272Y-118155D01*
X1084019Y-117572D01*
X1085765Y-118155D01*
X1087294Y-119614D01*
X1087949Y-121656D01*
X1087512Y-123697D01*
X1086421Y-125155D01*
X1085111Y-125739D01*
X1082927D01*
X1080962Y-126614D01*
X1079652Y-128364D01*
X1079216Y-130405D01*
X1079652Y-132448D01*
X1080744Y-133906D01*
X1082491Y-134780D01*
X1084019Y-135072D01*
G01X1097589Y-135655D02*
X1105449Y-117572D01*
G01X1119019D02*
X1117272Y-118155D01*
X1115962Y-119614D01*
X1115089Y-121363D01*
X1114434Y-123697D01*
X1114216Y-126322D01*
X1114434Y-128947D01*
X1115089Y-131281D01*
X1115962Y-133031D01*
X1117272Y-134489D01*
X1119019Y-135072D01*
X1120765Y-134489D01*
X1122076Y-133031D01*
X1122949Y-131281D01*
X1123604Y-128947D01*
X1123822Y-126322D01*
X1123604Y-123697D01*
X1122949Y-121363D01*
X1122076Y-119614D01*
X1120765Y-118155D01*
X1119019Y-117572D01*
G01X1136082Y-135072D02*
X1136519Y-131281D01*
X1137174Y-128072D01*
X1138047Y-125155D01*
X1139139Y-121947D01*
X1140886Y-117572D01*
X1132152D01*
G01X1150089Y-135655D02*
X1157949Y-117572D01*
G01X1167371Y-120489D02*
X1168681Y-118739D01*
X1170209Y-117864D01*
X1171956Y-117572D01*
X1174139Y-118155D01*
X1175667Y-119614D01*
X1176104Y-121363D01*
X1175886Y-123114D01*
X1175012Y-124572D01*
X1170646Y-127489D01*
X1168681Y-129530D01*
X1167371Y-132448D01*
X1166934Y-135072D01*
X1176104D01*
G01X1189019Y-117572D02*
X1187272Y-118155D01*
X1185962Y-119614D01*
X1185089Y-121363D01*
X1184434Y-123697D01*
X1184216Y-126322D01*
X1184434Y-128947D01*
X1185089Y-131281D01*
X1185962Y-133031D01*
X1187272Y-134489D01*
X1189019Y-135072D01*
X1190765Y-134489D01*
X1192076Y-133031D01*
X1192949Y-131281D01*
X1193604Y-128947D01*
X1193822Y-126322D01*
X1193604Y-123697D01*
X1192949Y-121363D01*
X1192076Y-119614D01*
X1190765Y-118155D01*
X1189019Y-117572D01*
G01X1206519Y-135072D02*
Y-117572D01*
X1203899Y-121072D01*
G01Y-135072D02*
X1209139D01*
G01X1223582D02*
X1224019Y-131281D01*
X1224674Y-128072D01*
X1225547Y-125155D01*
X1226639Y-121947D01*
X1228386Y-117572D01*
X1219652D01*
G01X1114216Y-90072D02*
Y-72572D01*
X1118582D01*
X1120329Y-73447D01*
X1121639Y-74614D01*
X1122731Y-76363D01*
X1123604Y-78406D01*
X1123822Y-81322D01*
X1123604Y-84239D01*
X1122731Y-86281D01*
X1121639Y-88031D01*
X1120329Y-89197D01*
X1118582Y-90072D01*
X1114216D01*
G01X1140449D02*
Y-78406D01*
G01Y-80447D02*
X1139576Y-79281D01*
X1138265Y-78697D01*
X1136737Y-78406D01*
X1135209Y-78989D01*
X1133899Y-80155D01*
X1133025Y-81905D01*
X1132589Y-84239D01*
X1133025Y-86572D01*
X1133899Y-88322D01*
X1135209Y-89489D01*
X1136737Y-90072D01*
X1138265Y-89780D01*
X1139576Y-88906D01*
X1140449Y-87739D01*
G01X1154019Y-72572D02*
Y-90072D01*
G01X1150962Y-78406D02*
X1157076D01*
G01X1168244Y-82197D02*
X1175231D01*
X1174576Y-80155D01*
X1173484Y-78989D01*
X1171956Y-78406D01*
X1170427Y-78697D01*
X1169117Y-79572D01*
X1168244Y-81614D01*
X1167807Y-83364D01*
Y-85114D01*
X1168244Y-86864D01*
X1169336Y-88614D01*
X1170646Y-89780D01*
X1172174Y-90072D01*
X1173702Y-89489D01*
X1175231Y-87739D01*
G01X3937Y0D02*
X116260D01*
G01X0Y3937D02*
G03X3937Y0I3937J0D01*
G01X0Y723480D02*
Y3937D01*
G01X416Y725241D02*
G03X0Y723480I3521J-1761D01*
G01X18597Y761603D02*
X416Y725241D01*
G01X77756Y98425D02*
G03X63976I-6890J0D01*
G01D02*
G03X77756I6890J0D01*
G01X83071Y245079D02*
G03Y231693I0J-6693D01*
G01X77756Y472441D02*
G03X63976I-6890J0D01*
G01D02*
G03X77756I6890J0D01*
G01X57087Y740157D02*
G03X41339I-7874J0D01*
G01D02*
G03X57087I7874J0D01*
G01X22118Y763780D02*
G03X18597Y761603I1J-3937D01*
G01X386149Y763780D02*
X22118D01*
G01X128071Y3937D02*
G03X132008Y0I3937J0D01*
G01X116260D02*
G03X120197Y3937I0J3937D01*
G01X132008Y0D02*
X275709D01*
G01X120197Y3937D02*
Y429331D01*
G01X128071Y59055D02*
Y3937D01*
G01Y59055D02*
G03X120197I-3937J0D01*
G01X128071D02*
G03X120197I-3937J0D01*
G01X128071Y98425D02*
Y421457D01*
G01X120197Y98425D02*
G03X128071I3937J0D01*
G01X120197D02*
G03X128071I3937J0D01*
G01X96457Y231693D02*
G03Y245079I0J6693D01*
G01X83071D02*
X96457D01*
G01Y231693D02*
X83071D01*
G01X96654Y413583D02*
G03X83661I-6496J0D01*
G01D02*
G03X96654I6496J0D01*
G01X132008Y425394D02*
G03X128071Y421457I0J-3937D01*
G01X124134Y433268D02*
X283583D01*
G01X124134D02*
G03X120197Y429331I0J-3937D01*
G01X184173Y425394D02*
X132008D01*
G01X213480Y37075D02*
G03I-4291J0D01*
G01Y383483D02*
G03I-4291J0D01*
G01X184173Y425394D02*
G03Y433268I0J3937D01*
G01Y425394D02*
G03Y433268I0J3937D01*
G01X171457Y669291D02*
G03X154921I-8268J0D01*
G01D02*
G03X171457I8268J0D01*
G01X223543Y425394D02*
X275709D01*
G01X223543Y433268D02*
G03Y425394I0J-3937D01*
G01Y433268D02*
G03Y425394I0J-3937D01*
G01X275709Y0D02*
G03X279646Y3937I0J3937D01*
G01X291457Y0D02*
X921260D01*
G01X287520Y3937D02*
G03X291457Y0I3937J0D01*
G01X287520Y429331D02*
Y3937D01*
G01X279646Y59055D02*
Y3937D01*
G01X287520Y59055D02*
G03X279646I-3937J0D01*
G01X287520D02*
G03X279646I-3937J0D01*
G01Y98425D02*
Y421457D01*
G01Y98425D02*
G03X287520I3937J0D01*
G01X279646D02*
G03X287520I3937J0D01*
G01X315551Y157677D02*
G03X302559I-6496J0D01*
G01D02*
G03X315551I6496J0D01*
G01X315945Y406890D02*
G03Y420276I0J6693D01*
G01X302559D02*
X315945D01*
G01X302559D02*
G03Y406890I0J-6693D01*
G01X315945D02*
X302559D01*
G01X279646Y421457D02*
G03X275709Y425394I-3937J0D01*
G01X287520Y429331D02*
G03X283583Y433268I-3937J0D01*
G01X321850Y472441D02*
G03X308071I-6889J0D01*
G01D02*
G03X321850I6889J0D01*
G01X412402Y39370D02*
G03X398622I-6890J0D01*
G01D02*
G03X412402I6890J0D01*
G01X371063Y740157D02*
G03X357283I-6890J0D01*
G01D02*
G03X371063I6890J0D01*
G01X403756Y763780D02*
G03X400235Y758082I0J-3937D01*
G01X389671Y761603D02*
G03X386149Y763780I-3522J-1760D01*
G01X414895Y728762D02*
X400235Y758082D01*
G01X407852Y725241D02*
X389671Y761603D01*
G01X403756Y763780D02*
X428096D01*
G01X416142Y200787D02*
G03X420079Y196850I3937J0D01*
G01X408268Y188976D02*
Y723480D01*
G01Y188976D02*
G03X412205I1968J0D01*
G01X556299Y196850D02*
X420079D01*
G01X564173Y188976D02*
X412205D01*
G01X416142Y316929D02*
Y200787D01*
G01Y316929D02*
G03X408268I-3937J0D01*
G01X416142D02*
G03X408268I-3937J0D01*
G01X416142Y347638D02*
Y690803D01*
G01X408268Y347638D02*
G03X416142I3937J0D01*
G01X408268D02*
G03X416142I3937J0D01*
G01Y721512D02*
Y723481D01*
G01Y723482D02*
G03X414894Y728764I-11811J-2D01*
G01X408268Y723480D02*
G03X407852Y725241I-3937J0D01*
G01X408268Y721512D02*
G03X416142I3937J0D01*
G01Y690803D02*
G03X408268I-3937J0D01*
G01Y721512D02*
G03X416142I3937J0D01*
G01Y690803D02*
G03X408268I-3937J0D01*
G01X428096Y763780D02*
G03X435970I3937J0D01*
G01D02*
X572622D01*
G01X483800Y137224D02*
G03X493878I5039J0D01*
G01X493563Y164744D02*
G03X484115I-4724J0D01*
G01D02*
G03X493563I4724J0D01*
G01X493878Y137224D02*
G03X483800I-5039J0D01*
G01X493622Y245605D02*
G03I-4291J0D01*
G01Y698924D02*
G03I-4291J0D01*
G01X556299Y196850D02*
G03X560236Y200787I0J3937D01*
G01X564173Y188976D02*
G03X568110I1968J0D01*
G01Y723480D02*
Y188976D01*
G01X560236Y316929D02*
Y200787D01*
G01X568110Y316929D02*
G03X560236I-3937J0D01*
G01X568110D02*
G03X560236I-3937J0D01*
G01Y690803D02*
Y347638D01*
G01D02*
G03X568110I3937J0D01*
G01X560236D02*
G03X568110I3937J0D01*
G01X560236Y721512D02*
Y723481D01*
G01X561484Y728764D02*
G03X560236Y723482I10563J-5284D01*
G01X568526Y725241D02*
G03X568110Y723480I3521J-1761D01*
G01X560236Y721512D02*
G03X568110I3937J0D01*
G01Y690803D02*
G03X560236I-3937J0D01*
G01Y721512D02*
G03X568110I3937J0D01*
G01Y690803D02*
G03X560236I-3937J0D01*
G01X576143Y758082D02*
G03X572622Y763780I-3521J1761D01*
G01X576143Y758082D02*
X561483Y728762D01*
G01X586707Y761603D02*
X568526Y725241D01*
G01X590228Y763780D02*
G03X586707Y761603I1J-3937D01*
G01X903079Y763780D02*
X590228D01*
G01X634252Y57874D02*
G03X625591I-4331J0D01*
G01D02*
G03X634252I4331J0D01*
G01X658661Y180000D02*
G03X646850I-5905J0D01*
G01D02*
G03X658661I5906J0D01*
G01X619094Y433071D02*
G03X605315I-6889J0D01*
G01D02*
G03X619094I6890J0D01*
G01Y740157D02*
G03X605315I-6889J0D01*
G01D02*
G03X619094I6890J0D01*
G01X712992Y57874D02*
G03X704331I-4331J0D01*
G01D02*
G03X712992I4330J0D01*
G01X859449Y332598D02*
G03X871260I5905J0D01*
G01D02*
G03X859449I-5906J0D01*
G01X921260Y0D02*
G03X925197Y3937I0J3937D01*
G01X883858Y59055D02*
G03X868110I-7874J0D01*
G01D02*
G03X883858I7874J0D01*
G01X925197Y3937D02*
Y723480D01*
G01X882874Y433071D02*
G03X869094I-6890J0D01*
G01D02*
G03X882874I6890J0D01*
G01X925197Y723480D02*
G03X924781Y725241I-3937J0D01*
G01X882874Y740157D02*
G03X869094I-6890J0D01*
G01D02*
G03X882874I6890J0D01*
G01X906600Y761603D02*
G03X903079Y763780I-3522J-1760D01*
G01X924781Y725241D02*
X906600Y761603D01*
G54D106*
X633216Y539027D03*
Y537059D03*
X621104D03*
Y539027D03*
G54D115*
X749030Y477405D03*
Y473468D03*
X738614Y475437D03*
G54D40*
X134700Y694750D03*
G54D13*
X58010Y49110D03*
X75373Y506479D03*
X75405Y514077D03*
X69900Y506600D03*
X69778Y514077D03*
X46100Y671584D03*
X79570Y55060D03*
X81032Y514077D03*
X81068Y506466D03*
X105920Y481998D03*
X86659Y514077D03*
X86673Y506600D03*
X92000Y514000D03*
X101100Y511900D03*
X101113Y519377D03*
X142000Y512100D03*
X93531Y492941D03*
X132100Y648000D03*
X136100D03*
X113349Y693647D03*
X117449D03*
X121549Y691347D03*
X193000Y503000D03*
X146112Y513098D03*
X183320Y478098D03*
X178920D03*
X174715Y517020D03*
X187000Y517000D03*
X191100Y516500D03*
X170700Y517000D03*
X166600D03*
X178869Y516993D03*
X182874Y516991D03*
X160727Y516822D03*
X150112Y513098D03*
X156721Y516792D03*
X188400Y502900D03*
X185276Y632868D03*
X177100Y633600D03*
X173000D03*
X202560Y624066D03*
X197315Y622397D03*
X153700Y622800D03*
X189376Y632868D03*
X193476D03*
X181146Y633608D03*
X188400Y644000D03*
X149300Y645000D03*
X204357Y653486D03*
X191746Y653642D03*
X165000Y644300D03*
X155849Y695715D03*
X158349Y703515D03*
X230262Y515280D03*
X234348Y515214D03*
X238648D03*
X242700Y515220D03*
X243400Y639500D03*
X248215Y613187D03*
X219200Y640600D03*
X231300Y642100D03*
X211706Y637992D03*
X251900Y676300D03*
X238936Y663469D03*
X258500Y675800D03*
X266800Y667600D03*
X262645Y704501D03*
X270900Y670600D03*
X300200Y590200D03*
X304300D03*
X293150Y535300D03*
X289050D03*
X336500Y670100D03*
X391262Y68871D03*
X386027Y68840D03*
X362484Y196719D03*
X349004Y179630D03*
X363553Y476262D03*
X382550Y581406D03*
X360820Y586836D03*
X352480Y586164D03*
X378350Y581406D03*
X345287Y537559D03*
X391549Y560200D03*
X387733Y594590D03*
X348600Y635600D03*
X444722Y50015D03*
X603164Y540803D03*
X639040Y157710D03*
X634661Y367356D03*
X620822Y372464D03*
X623239Y337479D03*
X608500Y336000D03*
X640160Y521843D03*
X619400Y563800D03*
X623542Y563752D03*
X732000Y189000D03*
X734028Y178946D03*
X716650Y177600D03*
X710060Y324860D03*
X727000Y346300D03*
X731400Y356000D03*
X711700Y345300D03*
X696527Y457306D03*
X696700Y469900D03*
X702390Y488860D03*
X731676Y587729D03*
X707826Y601479D03*
X716345Y608390D03*
X777700Y74200D03*
X795600Y188400D03*
X790600D03*
X762200Y188800D03*
X745700Y189000D03*
X737000D03*
X775500Y188300D03*
X749900Y188700D03*
X785600Y188400D03*
X738465Y346235D03*
X777000Y489100D03*
X751400Y500800D03*
X777084Y523050D03*
X809349Y66636D03*
X841300Y57880D03*
X813449Y66636D03*
X805600Y188400D03*
X800600D03*
X810600D03*
X857569Y384933D03*
X861000Y403400D03*
X882913Y228798D03*
G54D31*
X49900Y671384D03*
X117700Y515200D03*
X85500Y632700D03*
X81784Y667900D03*
X203650Y633050D03*
X207060Y629620D03*
X170100Y704600D03*
X210520Y629310D03*
X247400Y639400D03*
X225400Y713000D03*
X263000Y675700D03*
X328659Y536059D03*
X317600Y606800D03*
X322100Y641700D03*
X314920Y678920D03*
X311704Y712120D03*
X366699Y201221D03*
X521800Y49800D03*
X559200Y40500D03*
X633800Y337900D03*
X614000Y337300D03*
X645300Y526200D03*
X702460Y481050D03*
X728559Y474298D03*
X676194Y586129D03*
X723676Y587629D03*
X776200Y51200D03*
X786600Y416200D03*
X794500Y497600D03*
X757099Y522966D03*
X826284Y501900D03*
X883100Y221100D03*
G54D22*
X72577Y578589D03*
X69427D03*
X66278D03*
X72577Y581738D03*
X69427D03*
X66278D03*
X72577Y584888D03*
X69427D03*
X66278D03*
X72577Y540794D03*
X69427D03*
X66278D03*
X72577Y543943D03*
X69427D03*
X66278D03*
X72577Y537644D03*
X69427D03*
X66278D03*
X72577Y547093D03*
X69427D03*
X66278D03*
X72577Y550242D03*
X69427D03*
X66278D03*
X72577Y553392D03*
X69427D03*
X66278D03*
X72577Y556542D03*
X69427D03*
X66278D03*
X72577Y559691D03*
X69427D03*
X66278D03*
X72577Y562841D03*
X69427D03*
X66278D03*
X72577Y565990D03*
X69427D03*
X66278D03*
X72577Y569140D03*
X69427D03*
X66278D03*
X72577Y572290D03*
X69427D03*
X66278D03*
X72577Y575439D03*
X69427D03*
X66278D03*
X91474Y569140D03*
Y572290D03*
Y575439D03*
Y578589D03*
Y581738D03*
Y584888D03*
X88325Y578589D03*
X85175D03*
X88325Y581738D03*
X85175D03*
X88325Y584888D03*
X85175D03*
Y547093D03*
X91474Y540794D03*
X88325D03*
X85175D03*
X91474Y543943D03*
X88325D03*
X85175D03*
X91474Y537644D03*
X88325D03*
X85175D03*
X91474Y547093D03*
X88325D03*
X91474Y550242D03*
X88325D03*
X85175D03*
X91474Y553392D03*
X88325D03*
X85175D03*
X91474Y556542D03*
X88325D03*
X85175D03*
X91474Y559691D03*
X88325D03*
X85175D03*
X91474Y562841D03*
X88325D03*
X85175D03*
X91474Y565990D03*
X88325D03*
X85175D03*
X88325Y569140D03*
X85175D03*
X88325Y572290D03*
X85175D03*
X88325Y575439D03*
X85175D03*
X154724Y547244D03*
Y550394D03*
Y553543D03*
Y556693D03*
Y559842D03*
Y562992D03*
Y566142D03*
Y569291D03*
Y572441D03*
Y575590D03*
Y578740D03*
Y581890D03*
Y585039D03*
Y588189D03*
Y591338D03*
X157874Y547244D03*
Y550394D03*
Y553543D03*
Y556693D03*
Y559842D03*
Y562992D03*
Y566142D03*
Y569291D03*
Y572441D03*
Y575590D03*
Y578740D03*
Y581890D03*
Y585039D03*
Y588189D03*
Y591338D03*
X161023Y547244D03*
Y550394D03*
Y553543D03*
Y556693D03*
Y559842D03*
Y562992D03*
Y566142D03*
Y569291D03*
Y572441D03*
Y575590D03*
Y578740D03*
Y581890D03*
Y585039D03*
Y588189D03*
Y591338D03*
X164173Y537795D03*
Y540945D03*
Y544094D03*
Y547244D03*
Y550394D03*
Y553543D03*
Y556693D03*
Y559842D03*
Y562992D03*
Y566142D03*
Y569291D03*
Y572441D03*
Y575590D03*
Y578740D03*
Y581890D03*
Y585039D03*
Y588189D03*
Y591338D03*
X167323Y537795D03*
Y540945D03*
Y544094D03*
Y547244D03*
Y550394D03*
Y553543D03*
Y556693D03*
Y559842D03*
Y562992D03*
Y566142D03*
Y569291D03*
Y572441D03*
Y575590D03*
Y578740D03*
Y581890D03*
Y585039D03*
Y588189D03*
Y591338D03*
X170472Y537795D03*
Y540945D03*
Y544094D03*
Y547244D03*
Y550394D03*
Y553543D03*
Y556693D03*
Y559842D03*
Y562992D03*
Y566142D03*
Y569291D03*
Y572441D03*
Y575590D03*
Y578740D03*
Y581890D03*
Y585039D03*
Y588189D03*
Y591338D03*
X173622Y537795D03*
Y540945D03*
Y544094D03*
Y547244D03*
Y550394D03*
Y553543D03*
Y556693D03*
Y559842D03*
Y562992D03*
Y566142D03*
Y569291D03*
Y572441D03*
Y575590D03*
Y578740D03*
Y581890D03*
Y585039D03*
Y588189D03*
Y591338D03*
X176771Y537795D03*
Y540945D03*
Y544094D03*
Y547244D03*
Y550394D03*
Y553543D03*
Y556693D03*
Y585039D03*
Y588189D03*
Y591338D03*
X179921Y537795D03*
Y540945D03*
Y544094D03*
Y547244D03*
Y550394D03*
Y553543D03*
Y556693D03*
Y562992D03*
Y566142D03*
Y569291D03*
Y572441D03*
Y575590D03*
Y578740D03*
Y585039D03*
Y588189D03*
Y591338D03*
X183071Y537795D03*
Y540945D03*
Y544094D03*
Y547244D03*
Y550394D03*
Y553543D03*
Y556693D03*
Y562992D03*
Y566142D03*
Y569291D03*
Y572441D03*
Y575590D03*
Y578740D03*
Y585039D03*
Y588189D03*
Y591338D03*
X186220Y537795D03*
Y540945D03*
Y544094D03*
Y547244D03*
Y550394D03*
Y553543D03*
Y556693D03*
Y562992D03*
Y566142D03*
Y569291D03*
Y572441D03*
Y575590D03*
Y578740D03*
Y585039D03*
Y588189D03*
Y591338D03*
X189370Y537795D03*
Y540945D03*
Y544094D03*
Y547244D03*
Y550394D03*
Y553543D03*
Y556693D03*
Y562992D03*
Y566142D03*
Y569291D03*
Y572441D03*
Y575590D03*
Y578740D03*
Y585039D03*
Y588189D03*
Y591338D03*
X192519Y537795D03*
Y540945D03*
Y544094D03*
Y547244D03*
Y550394D03*
Y553543D03*
Y556693D03*
Y562992D03*
Y566142D03*
Y569291D03*
Y572441D03*
Y575590D03*
Y578740D03*
Y585039D03*
Y588189D03*
Y591338D03*
X195669Y537795D03*
Y540945D03*
Y544094D03*
Y547244D03*
Y550394D03*
Y553543D03*
Y556693D03*
Y562992D03*
Y566142D03*
Y569291D03*
Y572441D03*
Y575590D03*
Y578740D03*
Y585039D03*
Y588189D03*
Y591338D03*
X198819Y537795D03*
Y540945D03*
Y544094D03*
Y547244D03*
Y550394D03*
Y553543D03*
Y556693D03*
Y585039D03*
Y588189D03*
Y591338D03*
X201968Y537795D03*
Y540945D03*
Y544094D03*
Y547244D03*
Y550394D03*
Y553543D03*
Y556693D03*
Y559842D03*
Y562992D03*
Y566142D03*
Y569291D03*
Y572441D03*
Y575590D03*
Y578740D03*
Y581890D03*
Y585039D03*
Y588189D03*
Y591338D03*
X205118Y537795D03*
Y540945D03*
Y544094D03*
Y547244D03*
Y550394D03*
Y553543D03*
Y556693D03*
Y559842D03*
Y562992D03*
Y566142D03*
Y569291D03*
Y572441D03*
Y575590D03*
Y578740D03*
Y581890D03*
Y585039D03*
Y588189D03*
Y591338D03*
X208267Y537795D03*
Y540945D03*
Y544094D03*
Y547244D03*
Y550394D03*
Y553543D03*
Y556693D03*
Y559842D03*
Y562992D03*
Y566142D03*
Y569291D03*
Y572441D03*
Y575590D03*
Y578740D03*
Y581890D03*
Y585039D03*
Y588189D03*
Y591338D03*
X154724Y594488D03*
X157874D03*
X161023D03*
X164173D03*
Y597638D03*
Y600787D03*
Y603937D03*
X167323Y594488D03*
Y597638D03*
Y600787D03*
Y603937D03*
X170472Y594488D03*
Y597638D03*
Y600787D03*
Y603937D03*
X173622Y594488D03*
Y597638D03*
Y600787D03*
Y603937D03*
X176771Y594488D03*
Y597638D03*
Y600787D03*
Y603937D03*
X179921Y594488D03*
Y597638D03*
Y600787D03*
Y603937D03*
X183071Y594488D03*
Y597638D03*
Y600787D03*
Y603937D03*
X186220Y594488D03*
Y597638D03*
Y600787D03*
Y603937D03*
X189370Y594488D03*
Y597638D03*
Y600787D03*
Y603937D03*
X192519Y594488D03*
Y597638D03*
Y600787D03*
Y603937D03*
X195669Y594488D03*
Y597638D03*
Y600787D03*
Y603937D03*
X198819Y594488D03*
Y597638D03*
Y600787D03*
Y603937D03*
X201968Y594488D03*
Y597638D03*
Y600787D03*
Y603937D03*
X205118Y594488D03*
Y597638D03*
Y600787D03*
Y603937D03*
X208267Y594488D03*
Y597638D03*
Y600787D03*
Y603937D03*
X211417Y537795D03*
Y540945D03*
Y544094D03*
Y547244D03*
Y550394D03*
Y553543D03*
Y556693D03*
Y559842D03*
Y562992D03*
Y566142D03*
Y569291D03*
Y572441D03*
Y575590D03*
Y578740D03*
Y581890D03*
Y585039D03*
Y588189D03*
Y591338D03*
X214567Y547244D03*
Y550394D03*
Y553543D03*
Y556693D03*
Y559842D03*
Y562992D03*
Y566142D03*
Y569291D03*
Y572441D03*
Y575590D03*
Y578740D03*
Y581890D03*
Y585039D03*
Y588189D03*
Y591338D03*
X217716Y547244D03*
Y550394D03*
Y553543D03*
Y556693D03*
Y559842D03*
Y562992D03*
Y566142D03*
Y569291D03*
Y572441D03*
Y575590D03*
Y578740D03*
Y581890D03*
Y585039D03*
Y588189D03*
Y591338D03*
X220866Y547244D03*
Y550394D03*
Y553543D03*
Y556693D03*
Y559842D03*
Y562992D03*
Y566142D03*
Y569291D03*
Y572441D03*
Y575590D03*
Y578740D03*
Y581890D03*
Y585039D03*
Y588189D03*
Y591338D03*
X211417Y594488D03*
Y597638D03*
Y600787D03*
Y603937D03*
X214567Y594488D03*
X217716D03*
X220866D03*
X713386Y264173D03*
X716535D03*
X719685D03*
X722835D03*
X725984D03*
X729134D03*
X732283D03*
X713386Y261023D03*
X716535D03*
X719685D03*
X722835D03*
X725984D03*
X729134D03*
X732283D03*
X713386Y257874D03*
X716535D03*
X719685D03*
X722835D03*
X725984D03*
X729134D03*
X732283D03*
X713386Y254724D03*
X716535D03*
X719685D03*
X722835D03*
X725984D03*
X729134D03*
X732283D03*
X713386Y251575D03*
X716535D03*
X719685D03*
X722835D03*
X725984D03*
X729134D03*
X732283D03*
X713386Y248425D03*
X716535D03*
X719685D03*
X722835D03*
X725984D03*
X729134D03*
X732283D03*
X713386Y245275D03*
X716535D03*
X719685D03*
X722835D03*
X725984D03*
X729134D03*
X732283D03*
X713386Y242126D03*
X716535D03*
X719685D03*
X722835D03*
X725984D03*
X729134D03*
X732283D03*
X713386Y238976D03*
X716535D03*
X719685D03*
X722835D03*
X725984D03*
X729134D03*
X732283D03*
X713386Y235827D03*
X716535D03*
X719685D03*
X722835D03*
X725984D03*
X729134D03*
X732283D03*
X713386Y232677D03*
X716535D03*
X719685D03*
X722835D03*
X725984D03*
X729134D03*
X732283D03*
X713386Y229527D03*
X716535D03*
X719685D03*
X722835D03*
X725984D03*
X729134D03*
X732283D03*
X713386Y226378D03*
X716535D03*
X719685D03*
X722835D03*
X725984D03*
X729134D03*
X732283D03*
X713386Y223228D03*
X716535D03*
X719685D03*
X722835D03*
X725984D03*
X729134D03*
X732283D03*
X713386Y220079D03*
X716535D03*
X719685D03*
X722835D03*
X725984D03*
X729134D03*
X732283D03*
X722835Y216929D03*
X725984D03*
X729134D03*
X732283D03*
X722835Y213779D03*
X725984D03*
X729134D03*
X732283D03*
X722835Y210630D03*
X725984D03*
X729134D03*
X732283D03*
X722835Y301968D03*
X725984D03*
X729134D03*
X732283D03*
X722835Y298819D03*
X725984D03*
X729134D03*
X732283D03*
X722835Y295669D03*
X725984D03*
X729134D03*
X732283D03*
X713386Y292519D03*
X716535D03*
X719685D03*
X722835D03*
X725984D03*
X729134D03*
X732283D03*
X713386Y289370D03*
X716535D03*
X719685D03*
X722835D03*
X725984D03*
X729134D03*
X732283D03*
X713386Y286220D03*
X716535D03*
X719685D03*
X722835D03*
X725984D03*
X729134D03*
X732283D03*
X713386Y283071D03*
X716535D03*
X719685D03*
X722835D03*
X725984D03*
X729134D03*
X732283D03*
X713386Y279921D03*
X716535D03*
X719685D03*
X722835D03*
X725984D03*
X729134D03*
X732283D03*
X713386Y276771D03*
X716535D03*
X719685D03*
X722835D03*
X725984D03*
X729134D03*
X732283D03*
X713386Y273622D03*
X716535D03*
X719685D03*
X722835D03*
X725984D03*
X729134D03*
X732283D03*
X713386Y270472D03*
X716535D03*
X719685D03*
X722835D03*
X725984D03*
X729134D03*
X732283D03*
X713386Y267323D03*
X716535D03*
X719685D03*
X722835D03*
X725984D03*
X729134D03*
X732283D03*
X735433Y264173D03*
X738583D03*
X741732D03*
X744882D03*
X748031D03*
X751181D03*
X754331D03*
X757480D03*
X760630D03*
X763779D03*
X766929D03*
X770079D03*
X773228D03*
X776378D03*
X779527D03*
X782677D03*
X785827D03*
X788976D03*
X792126D03*
X795275D03*
X798425D03*
X735433Y261023D03*
X738583D03*
X741732D03*
X744882D03*
X748031D03*
X751181D03*
X754331D03*
X757480D03*
X760630D03*
X763779D03*
X766929D03*
X770079D03*
X773228D03*
X776378D03*
X779527D03*
X782677D03*
X785827D03*
X788976D03*
X792126D03*
X795275D03*
X798425D03*
X735433Y257874D03*
X738583D03*
X741732D03*
X744882D03*
X748031D03*
X751181D03*
X754331D03*
X757480D03*
X760630D03*
X763779D03*
X766929D03*
X770079D03*
X773228D03*
X776378D03*
X779527D03*
X782677D03*
X785827D03*
X788976D03*
X792126D03*
X795275D03*
X798425D03*
X735433Y254724D03*
X738583D03*
X741732D03*
X744882D03*
X748031D03*
X751181D03*
X754331D03*
X757480D03*
X760630D03*
X763779D03*
X766929D03*
X770079D03*
X773228D03*
X776378D03*
X779527D03*
X782677D03*
X785827D03*
X788976D03*
X792126D03*
X795275D03*
X798425D03*
X735433Y251575D03*
X738583D03*
X741732D03*
X744882D03*
X748031D03*
X751181D03*
X754331D03*
X757480D03*
X760630D03*
X763779D03*
X766929D03*
X770079D03*
X773228D03*
X776378D03*
X779527D03*
X782677D03*
X785827D03*
X788976D03*
X792126D03*
X795275D03*
X798425D03*
X735433Y248425D03*
X738583D03*
X741732D03*
X744882D03*
X748031D03*
X751181D03*
X754331D03*
X757480D03*
X760630D03*
X763779D03*
X766929D03*
X770079D03*
X773228D03*
X776378D03*
X779527D03*
X782677D03*
X785827D03*
X788976D03*
X792126D03*
X795275D03*
X798425D03*
X735433Y245275D03*
X738583D03*
X741732D03*
X744882D03*
X748031D03*
X751181D03*
X754331D03*
X757480D03*
X760630D03*
X763779D03*
X766929D03*
X770079D03*
X773228D03*
X776378D03*
X779527D03*
X782677D03*
X785827D03*
X788976D03*
X792126D03*
X795275D03*
X798425D03*
X735433Y242126D03*
X738583D03*
X741732D03*
X744882D03*
X748031D03*
X751181D03*
X754331D03*
X757480D03*
X760630D03*
X763779D03*
X766929D03*
X770079D03*
X773228D03*
X776378D03*
X779527D03*
X782677D03*
X785827D03*
X788976D03*
X792126D03*
X795275D03*
X798425D03*
X735433Y238976D03*
X738583D03*
X741732D03*
X744882D03*
X748031D03*
X751181D03*
X754331D03*
X757480D03*
X760630D03*
X763779D03*
X766929D03*
X770079D03*
X773228D03*
X776378D03*
X779527D03*
X782677D03*
X785827D03*
X788976D03*
X792126D03*
X795275D03*
X798425D03*
X735433Y235827D03*
X738583D03*
X741732D03*
X744882D03*
X748031D03*
X751181D03*
X754331D03*
X757480D03*
X760630D03*
X763779D03*
X766929D03*
X770079D03*
X773228D03*
X776378D03*
X779527D03*
X782677D03*
X785827D03*
X788976D03*
X792126D03*
X795275D03*
X798425D03*
X735433Y232677D03*
X738583D03*
X741732D03*
X744882D03*
X748031D03*
X751181D03*
X754331D03*
X757480D03*
X760630D03*
X763779D03*
X766929D03*
X770079D03*
X773228D03*
X776378D03*
X779527D03*
X782677D03*
X785827D03*
X788976D03*
X792126D03*
X795275D03*
X798425D03*
X735433Y229527D03*
X738583D03*
X741732D03*
X744882D03*
X748031D03*
X751181D03*
X754331D03*
X757480D03*
X760630D03*
X763779D03*
X766929D03*
X770079D03*
X773228D03*
X776378D03*
X779527D03*
X782677D03*
X785827D03*
X788976D03*
X792126D03*
X795275D03*
X798425D03*
X735433Y226378D03*
X738583D03*
X741732D03*
X744882D03*
X748031D03*
X751181D03*
X754331D03*
X757480D03*
X760630D03*
X763779D03*
X766929D03*
X770079D03*
X773228D03*
X776378D03*
X779527D03*
X782677D03*
X785827D03*
X788976D03*
X792126D03*
X795275D03*
X798425D03*
X735433Y223228D03*
X738583D03*
X741732D03*
X744882D03*
X748031D03*
X751181D03*
X754331D03*
X757480D03*
X760630D03*
X763779D03*
X766929D03*
X770079D03*
X773228D03*
X776378D03*
X779527D03*
X782677D03*
X785827D03*
X788976D03*
X792126D03*
X795275D03*
X798425D03*
X735433Y220079D03*
X738583D03*
X741732D03*
X744882D03*
X748031D03*
X751181D03*
X754331D03*
X757480D03*
X760630D03*
X763779D03*
X766929D03*
X770079D03*
X773228D03*
X776378D03*
X779527D03*
X782677D03*
X785827D03*
X788976D03*
X792126D03*
X795275D03*
X798425D03*
X735433Y216929D03*
X738583D03*
X741732D03*
X744882D03*
X748031D03*
X751181D03*
X754331D03*
X757480D03*
X760630D03*
X763779D03*
X766929D03*
X770079D03*
X773228D03*
X776378D03*
X779527D03*
X782677D03*
X785827D03*
X788976D03*
X792126D03*
X795275D03*
X735433Y213779D03*
X738583D03*
X741732D03*
X744882D03*
X748031D03*
X751181D03*
X754331D03*
X757480D03*
X760630D03*
X763779D03*
X766929D03*
X770079D03*
X773228D03*
X776378D03*
X779527D03*
X782677D03*
X785827D03*
X788976D03*
X792126D03*
X795275D03*
X735433Y210630D03*
X738583D03*
X741732D03*
X744882D03*
X748031D03*
X751181D03*
X754331D03*
X757480D03*
X760630D03*
X763779D03*
X766929D03*
X770079D03*
X773228D03*
X776378D03*
X779527D03*
X782677D03*
X785827D03*
X788976D03*
X792126D03*
X795275D03*
X735433Y301968D03*
X738583D03*
X741732D03*
X744882D03*
X748031D03*
X751181D03*
X754331D03*
X757480D03*
X760630D03*
X763779D03*
X766929D03*
X770079D03*
X773228D03*
X776378D03*
X779527D03*
X782677D03*
X785827D03*
X788976D03*
X792126D03*
X795275D03*
X735433Y298819D03*
X738583D03*
X741732D03*
X744882D03*
X748031D03*
X751181D03*
X754331D03*
X757480D03*
X760630D03*
X763779D03*
X766929D03*
X770079D03*
X773228D03*
X776378D03*
X779527D03*
X782677D03*
X785827D03*
X788976D03*
X792126D03*
X795275D03*
X735433Y295669D03*
X738583D03*
X741732D03*
X744882D03*
X748031D03*
X751181D03*
X754331D03*
X757480D03*
X760630D03*
X763779D03*
X766929D03*
X770079D03*
X773228D03*
X776378D03*
X779527D03*
X782677D03*
X785827D03*
X788976D03*
X792126D03*
X795275D03*
X735433Y292519D03*
X738583D03*
X741732D03*
X744882D03*
X748031D03*
X751181D03*
X754331D03*
X757480D03*
X760630D03*
X763779D03*
X766929D03*
X770079D03*
X773228D03*
X776378D03*
X779527D03*
X782677D03*
X785827D03*
X788976D03*
X792126D03*
X795275D03*
X798425D03*
X735433Y289370D03*
X738583D03*
X741732D03*
X744882D03*
X748031D03*
X751181D03*
X754331D03*
X757480D03*
X760630D03*
X763779D03*
X766929D03*
X770079D03*
X773228D03*
X776378D03*
X779527D03*
X782677D03*
X785827D03*
X788976D03*
X792126D03*
X795275D03*
X798425D03*
X735433Y286220D03*
X738583D03*
X741732D03*
X744882D03*
X748031D03*
X751181D03*
X754331D03*
X757480D03*
X760630D03*
X763779D03*
X766929D03*
X770079D03*
X773228D03*
X776378D03*
X779527D03*
X782677D03*
X785827D03*
X788976D03*
X792126D03*
X795275D03*
X798425D03*
X735433Y283071D03*
X738583D03*
X741732D03*
X744882D03*
X748031D03*
X751181D03*
X754331D03*
X757480D03*
X760630D03*
X763779D03*
X766929D03*
X770079D03*
X773228D03*
X776378D03*
X779527D03*
X782677D03*
X785827D03*
X788976D03*
X792126D03*
X795275D03*
X798425D03*
X735433Y279921D03*
X738583D03*
X741732D03*
X744882D03*
X748031D03*
X751181D03*
X754331D03*
X757480D03*
X760630D03*
X763779D03*
X766929D03*
X770079D03*
X773228D03*
X776378D03*
X779527D03*
X782677D03*
X785827D03*
X788976D03*
X792126D03*
X795275D03*
X798425D03*
X735433Y276771D03*
X738583D03*
X741732D03*
X744882D03*
X748031D03*
X751181D03*
X754331D03*
X757480D03*
X760630D03*
X763779D03*
X766929D03*
X770079D03*
X773228D03*
X776378D03*
X779527D03*
X782677D03*
X785827D03*
X788976D03*
X792126D03*
X795275D03*
X798425D03*
X735433Y273622D03*
X738583D03*
X741732D03*
X744882D03*
X748031D03*
X751181D03*
X754331D03*
X757480D03*
X760630D03*
X763779D03*
X766929D03*
X770079D03*
X773228D03*
X776378D03*
X779527D03*
X782677D03*
X785827D03*
X788976D03*
X792126D03*
X795275D03*
X798425D03*
X735433Y270472D03*
X738583D03*
X741732D03*
X744882D03*
X748031D03*
X751181D03*
X754331D03*
X757480D03*
X760630D03*
X763779D03*
X766929D03*
X770079D03*
X773228D03*
X776378D03*
X779527D03*
X782677D03*
X785827D03*
X788976D03*
X792126D03*
X795275D03*
X798425D03*
X735433Y267323D03*
X738583D03*
X741732D03*
X744882D03*
X748031D03*
X751181D03*
X754331D03*
X757480D03*
X760630D03*
X763779D03*
X766929D03*
X770079D03*
X773228D03*
X776378D03*
X779527D03*
X782677D03*
X785827D03*
X788976D03*
X792126D03*
X795275D03*
X798425D03*
X801575Y264173D03*
X804724D03*
X801575Y261023D03*
X804724D03*
X801575Y257874D03*
X804724D03*
X801575Y254724D03*
X804724D03*
X801575Y251575D03*
X804724D03*
X801575Y248425D03*
X804724D03*
X801575Y245275D03*
X804724D03*
X801575Y242126D03*
X804724D03*
X801575Y238976D03*
X804724D03*
X801575Y235827D03*
X804724D03*
X801575Y232677D03*
X804724D03*
X801575Y229527D03*
X804724D03*
X801575Y226378D03*
X804724D03*
X801575Y223228D03*
X804724D03*
X801575Y220079D03*
X804724D03*
X801575Y292519D03*
X804724D03*
X801575Y289370D03*
X804724D03*
X801575Y286220D03*
X804724D03*
X801575Y283071D03*
X804724D03*
X801575Y279921D03*
X804724D03*
X801575Y276771D03*
X804724D03*
X801575Y273622D03*
X804724D03*
X801575Y270472D03*
X804724D03*
X801575Y267323D03*
X804724D03*
G54D50*
X197087Y679921D03*
G54D14*
X43480Y53750D03*
X71800Y691500D03*
X84616Y60475D03*
X93614Y507152D03*
X115619Y712795D03*
X295018Y661382D03*
X278523Y736205D03*
X353972Y192744D03*
X352980Y641914D03*
X453800Y61500D03*
X533940Y73210D03*
X563870Y55203D03*
X628160Y565343D03*
X612500Y540600D03*
X724900Y493800D03*
X720200D03*
X751500Y54030D03*
X767247Y502427D03*
X800388Y522956D03*
G54D32*
X65714Y665850D03*
X306300Y638600D03*
X295634Y710070D03*
X810214Y499850D03*
G54D107*
X630113Y531937D03*
X624207D03*
Y544149D03*
X630113D03*
G54D23*
X50050Y529400D03*
X55895Y643491D03*
X73265Y647355D03*
X49300Y656600D03*
X34300Y677500D03*
X76264Y685964D03*
X46043Y679557D03*
X88900Y498700D03*
X103800Y570500D03*
X126870Y598031D03*
X139959Y606009D03*
X139971Y614874D03*
X112850Y641488D03*
X128793Y613483D03*
X139728Y596666D03*
X83450Y646620D03*
X144550Y618316D03*
X123534Y593743D03*
X117000Y597000D03*
X115006Y625751D03*
X139679Y601454D03*
X144000Y645600D03*
X127900Y643420D03*
X134700Y643441D03*
X127597Y693231D03*
X117767Y702633D03*
X121501Y699049D03*
X106400Y722900D03*
X138653Y739871D03*
X144249Y733200D03*
X199755Y524755D03*
X194803Y525639D03*
X187000Y524214D03*
X188584Y528105D03*
X177017Y526942D03*
X172800Y524100D03*
X170200Y527400D03*
X182000Y527362D03*
X162800Y527600D03*
X153812Y526926D03*
X158100Y524100D03*
X210000Y510000D03*
X204752Y524566D03*
X145100Y539800D03*
X145012Y544801D03*
X145100Y549900D03*
X205000Y614500D03*
X194200Y613700D03*
X189185Y617400D03*
X185085Y613700D03*
X182200Y617100D03*
X178800Y614100D03*
X175040Y616035D03*
X163300Y629800D03*
X197315Y617778D03*
X201449Y619094D03*
X149250Y618050D03*
X153901Y617796D03*
X158898Y617993D03*
X160200Y639600D03*
X156238Y643866D03*
X160249Y699165D03*
X144662Y697593D03*
X269600Y523350D03*
X225300Y527900D03*
X231800Y522500D03*
X221800Y523700D03*
X221187Y516937D03*
X213487Y524273D03*
X272723Y540752D03*
X230940Y565901D03*
X236700Y562800D03*
X235339Y568279D03*
X235721Y575076D03*
X236210Y584419D03*
X232763Y579124D03*
X231200Y559800D03*
X267200Y548200D03*
X259800Y528926D03*
X257161Y559865D03*
X250700Y530500D03*
X241300Y585000D03*
X231204Y529404D03*
X267200Y576400D03*
X240800Y528500D03*
X252590Y538010D03*
X211600Y614400D03*
X216000Y622450D03*
X223593Y634091D03*
X220400Y654600D03*
X214500Y626500D03*
X220614Y616544D03*
X233300Y618300D03*
X238000Y617896D03*
X237000Y597400D03*
X275500Y652348D03*
X240300Y613737D03*
X238950Y651600D03*
X252492Y643414D03*
X264683Y638810D03*
X273467Y657050D03*
X248600Y699300D03*
X256900Y699715D03*
X275349Y723500D03*
X256666Y716225D03*
X271240Y680097D03*
X267350Y710224D03*
X247400Y679150D03*
X221987Y728528D03*
X222306Y737851D03*
X338882Y248674D03*
X340500Y236600D03*
X338982Y243274D03*
X338751Y268585D03*
X339182Y273077D03*
X289500Y451900D03*
X337600Y494968D03*
X318778Y510778D03*
X301620Y515600D03*
X287615Y524997D03*
X340800Y504200D03*
X287271Y545971D03*
X287200Y553300D03*
X306364Y574464D03*
X307519Y584195D03*
X307385Y559544D03*
X307187Y566066D03*
X303091Y568720D03*
X301365Y573221D03*
X298308Y530131D03*
X281158Y538858D03*
X309417Y589500D03*
X323956Y539616D03*
X299294Y542868D03*
X322511Y544355D03*
X320031Y535663D03*
X301216Y535004D03*
X299200Y597400D03*
X290399Y656015D03*
X289917Y649778D03*
X301700Y608000D03*
X314390Y620830D03*
X285988Y637449D03*
X281300Y670200D03*
X282600Y674600D03*
X286500Y693500D03*
X309090Y690532D03*
X276325Y705863D03*
X339731Y682730D03*
X301054Y666724D03*
X340583Y670807D03*
X283080Y730387D03*
X374014Y188823D03*
X353762Y181744D03*
X344388Y179571D03*
X362727Y192756D03*
X352017Y263432D03*
X383140Y367158D03*
X360446Y358846D03*
X361176Y379610D03*
X354850Y376362D03*
X369300Y362600D03*
X383900Y422100D03*
X390999Y461382D03*
X352700Y498400D03*
X360400Y470400D03*
X395928Y482925D03*
X377644Y491967D03*
X343000Y492100D03*
X344700Y522600D03*
X376700Y480300D03*
X368543Y479991D03*
X360374Y486117D03*
X352490Y515908D03*
X387561Y540889D03*
X355400Y593400D03*
X372700Y593600D03*
X379628Y589070D03*
X375771Y590734D03*
X383622Y590370D03*
X384746Y547941D03*
X349700Y577400D03*
X386835Y563988D03*
X351030Y536681D03*
X345443Y531460D03*
X365270Y580800D03*
X349334Y557789D03*
X349005Y549206D03*
X385845Y614925D03*
X383127Y595147D03*
X383271Y605000D03*
X388300Y632700D03*
X383168Y626894D03*
X346485Y676801D03*
X383885Y684055D03*
X381888Y678912D03*
X381377Y672923D03*
X380900Y692940D03*
X451500Y28000D03*
X451800Y23000D03*
X467800Y58000D03*
X448859Y42351D03*
X452293Y50940D03*
X460024Y18801D03*
X450900Y33300D03*
X458662Y53326D03*
X470599Y71247D03*
X469653Y88700D03*
X445163Y102450D03*
X456430Y87000D03*
X516600Y49650D03*
X517825Y54994D03*
X521155Y19621D03*
X497990Y54540D03*
X512542Y19091D03*
X473100Y58000D03*
X483235Y36335D03*
X484414Y26637D03*
X476305Y53965D03*
X484965Y63428D03*
X485104Y21491D03*
X481831Y17711D03*
X498150Y26850D03*
X489730Y77724D03*
X494171Y73533D03*
X475310Y89843D03*
X565100Y60400D03*
X551200Y47300D03*
X564100Y44203D03*
X581476Y43046D03*
X549650Y67500D03*
X582090Y58780D03*
X574759Y68489D03*
X555327Y81900D03*
X588676Y373300D03*
X602860Y522543D03*
X640600Y151600D03*
X607400Y299100D03*
X639878Y348571D03*
X618900Y338200D03*
X620139Y380400D03*
X620111Y367921D03*
X608500Y343300D03*
X612466Y368519D03*
X653449Y360181D03*
X632220Y393520D03*
X640960Y377294D03*
X643200Y366300D03*
X603597Y335950D03*
X614022Y382345D03*
X626262Y377540D03*
X655800Y400550D03*
X640891Y414908D03*
X632180Y401800D03*
X635480Y526130D03*
X621108Y520852D03*
X640160Y517269D03*
X647359Y560063D03*
X607676Y540800D03*
X625398Y550500D03*
X634384Y550513D03*
X623327Y559229D03*
X603831Y548331D03*
X639500Y540500D03*
X639300Y532700D03*
X641380Y693090D03*
X647413Y697494D03*
X720878Y180410D03*
X717700Y196400D03*
X710403Y197200D03*
X706357Y180801D03*
X690000Y249500D03*
X690094Y243050D03*
X699145Y258217D03*
X704000Y244800D03*
X694500Y254517D03*
X704508Y233964D03*
X703452Y200958D03*
X694150Y267984D03*
X693668Y278378D03*
X689809Y290474D03*
X703130Y268891D03*
X693300Y273000D03*
X718427Y358980D03*
X709008Y354239D03*
X728038Y336182D03*
X733036Y351439D03*
X675130Y381713D03*
X714200Y445400D03*
X703617Y431443D03*
X683048Y443658D03*
X726211Y483619D03*
X729365Y488535D03*
X696100Y499100D03*
X696500Y465373D03*
X676418Y475383D03*
X681639Y499750D03*
X675300Y499000D03*
X697095Y480132D03*
X729346Y573866D03*
X718551Y555953D03*
X669294Y579571D03*
X706600Y546800D03*
X714777Y561129D03*
X717314Y587242D03*
X714978Y547961D03*
X693500Y554300D03*
X693484Y654328D03*
X733872Y629500D03*
X711081Y595223D03*
X723415Y621166D03*
X720300Y615300D03*
X693405Y676551D03*
X681740Y705064D03*
X752331Y61071D03*
X777666Y43729D03*
X786200Y60535D03*
X766542Y44076D03*
X761600Y68300D03*
X797500Y48500D03*
X783350Y80050D03*
X757100Y113000D03*
X766260Y92788D03*
X776200Y93050D03*
X789000Y100400D03*
X776300Y110100D03*
X778760Y123150D03*
X745300Y196300D03*
X765800Y196847D03*
X746891Y200751D03*
X755729Y201712D03*
X761780Y201451D03*
X741500Y201840D03*
X782693Y431308D03*
X744806Y495350D03*
X758100Y478184D03*
X744018Y516886D03*
X754462Y496762D03*
X771200Y492800D03*
X761200Y511300D03*
X739900Y505700D03*
X758901Y488563D03*
X753519Y508069D03*
X767300Y473700D03*
X795922Y518640D03*
X790200Y514000D03*
X793700Y493400D03*
X784500Y518694D03*
X736394Y593579D03*
X754775Y538079D03*
X790459Y538770D03*
X777100Y531200D03*
X814900Y61800D03*
X809000Y62000D03*
X824200Y48300D03*
X836400Y61300D03*
X858820Y232979D03*
X827988Y238779D03*
X851700Y382900D03*
X857664Y395138D03*
X822958Y393800D03*
X843619Y378326D03*
X856463Y399163D03*
X822900Y399400D03*
X823256Y406365D03*
X810341Y398947D03*
X813974Y404934D03*
X831489Y510582D03*
X800389Y482153D03*
X819036Y481398D03*
X892850Y313349D03*
X881200Y316000D03*
X887703Y300225D03*
X867602Y368048D03*
G54D116*
X741114Y479374D03*
G54D41*
X134700Y697450D03*
G54D24*
X64884Y643900D03*
X148700Y691600D03*
X204286Y698355D03*
X146649Y740015D03*
X275600Y715100D03*
X298400Y524750D03*
X302919Y553653D03*
X294300Y543000D03*
X305670Y612350D03*
X285460Y644250D03*
X294804Y688120D03*
X380800Y543200D03*
X362586Y639880D03*
X353830Y702620D03*
X446135Y34357D03*
X630322Y368128D03*
X613710Y521543D03*
X620300Y467000D03*
X625460Y554943D03*
X642900Y557500D03*
X744630Y452700D03*
X818034Y389702D03*
X809500Y477200D03*
G54D42*
X135019Y714845D03*
G54D51*
X207795Y670886D03*
X203858D03*
X209764Y688956D03*
X205827D03*
X223544Y670886D03*
X219607D03*
X215670D03*
X211732D03*
X221575Y688956D03*
X217638D03*
X213701D03*
G54D60*
X243199Y718747D03*
X232199D03*
X243199Y737947D03*
X232199D03*
X243199Y728347D03*
X232199D03*
X766680Y119860D03*
X755680D03*
G54D108*
X628144Y531987D03*
X626176D03*
Y544099D03*
X628144D03*
G54D33*
X55971Y660732D03*
Y663291D03*
Y665850D03*
Y668409D03*
Y670968D03*
X75457D03*
Y668409D03*
Y665850D03*
Y663291D03*
Y660732D03*
X296557Y633482D03*
Y636041D03*
Y638600D03*
Y641159D03*
Y643718D03*
X316043D03*
Y641159D03*
Y638600D03*
Y636041D03*
Y633482D03*
X285891Y704952D03*
Y707511D03*
Y710070D03*
Y712629D03*
Y715188D03*
X305377D03*
Y712629D03*
Y710070D03*
Y707511D03*
Y704952D03*
X800471Y494732D03*
Y497291D03*
Y499850D03*
Y502409D03*
Y504968D03*
X819957D03*
Y502409D03*
Y499850D03*
Y497291D03*
Y494732D03*
G54D117*
X752180Y485279D03*
Y483311D03*
Y481342D03*
Y479374D03*
X735464Y485279D03*
Y481342D03*
Y483311D03*
G54D15*
X43480Y48150D03*
X71800Y685900D03*
X84616Y54875D03*
X93614Y501552D03*
X115619Y707195D03*
X295018Y655782D03*
X278523Y730605D03*
X353972Y187144D03*
X352980Y636314D03*
X453800Y55900D03*
X533940Y67610D03*
X563870Y49603D03*
X628160Y559743D03*
X612500Y535000D03*
X724900Y488200D03*
X720200D03*
X751500Y48430D03*
X767247Y496827D03*
X800388Y517356D03*
G54D25*
X61284Y643900D03*
X143049Y740015D03*
X145100Y691600D03*
X200686Y698355D03*
X272000Y715100D03*
X294800Y524750D03*
X299319Y553653D03*
X290700Y543000D03*
X302070Y612350D03*
X281860Y644250D03*
X291204Y688120D03*
X377200Y543200D03*
X358986Y639880D03*
X350230Y702620D03*
X442535Y34357D03*
X626722Y368128D03*
X610110Y521543D03*
X616700Y467000D03*
X621860Y554943D03*
X639300Y557500D03*
X741030Y452700D03*
X814434Y389702D03*
X805900Y477200D03*
G54D52*
X197920Y712091D03*
Y736891D03*
X367762Y131001D03*
Y155801D03*
X833400Y451600D03*
Y426800D03*
X808200Y451600D03*
Y426800D03*
G54D109*
X653700Y653200D03*
Y673400D03*
X678500Y653200D03*
Y673400D03*
G54D34*
X125481Y460299D03*
Y465299D03*
Y470299D03*
Y475299D03*
Y480299D03*
Y485299D03*
Y490299D03*
Y495299D03*
X164039Y460299D03*
Y495299D03*
Y490299D03*
Y485299D03*
Y480299D03*
Y475299D03*
Y470299D03*
Y465299D03*
X220521Y460300D03*
X259079D03*
X220521Y465300D03*
Y470300D03*
Y475300D03*
Y480300D03*
Y485300D03*
Y490300D03*
Y495300D03*
X259079D03*
Y490300D03*
Y485300D03*
Y480300D03*
Y475300D03*
Y470300D03*
Y465300D03*
G54D43*
X125376Y705002D03*
Y706971D03*
Y708939D03*
Y710908D03*
Y712876D03*
Y714845D03*
Y716814D03*
Y718782D03*
Y720751D03*
Y722719D03*
X144662D03*
Y720751D03*
Y718782D03*
Y716814D03*
Y714845D03*
Y712876D03*
Y710908D03*
Y708939D03*
Y706971D03*
Y705002D03*
X125376Y724688D03*
X144662D03*
G54D16*
X34070Y48070D03*
Y54070D03*
X93640Y54860D03*
Y60860D03*
G54D61*
X274200Y663600D03*
X283200D03*
G54D118*
X750712Y488716D03*
X748743D03*
X738901D03*
X736932D03*
X740869D03*
X742838D03*
X744806D03*
X746775D03*
G54D70*
X374768Y53823D03*
Y49223D03*
X374594Y84695D03*
Y80095D03*
G54D26*
X77766Y637546D03*
Y629946D03*
X83750Y654654D03*
X91550Y654554D03*
X83750Y662254D03*
X91550Y662154D03*
X101749Y730715D03*
Y738315D03*
X94020Y730691D03*
Y738291D03*
X124820Y732391D03*
Y739991D03*
X109449Y730715D03*
Y738315D03*
X117149Y730715D03*
Y738315D03*
X132651Y732415D03*
Y740015D03*
X219600Y717700D03*
Y710100D03*
X211800Y717700D03*
Y710100D03*
X324636Y627604D03*
Y635204D03*
X332436Y627504D03*
Y635104D03*
X319536Y658504D03*
X311636D03*
X311936Y609096D03*
Y601496D03*
X321470Y698774D03*
Y706374D03*
X313670Y698874D03*
Y706474D03*
X319536Y666104D03*
X311636D03*
X309300Y683100D03*
Y675500D03*
X298470Y731174D03*
Y738774D03*
X306370Y731174D03*
Y738774D03*
X659600Y523200D03*
X651500D03*
X659600Y530800D03*
X651500D03*
X692000Y529500D03*
Y537100D03*
X742700Y457680D03*
Y465280D03*
X821050Y519654D03*
Y527254D03*
X813150Y519654D03*
Y527254D03*
X828250Y488954D03*
Y496554D03*
X836050Y488854D03*
Y496454D03*
G54D35*
X126185Y460299D03*
Y495299D03*
Y490299D03*
Y485299D03*
Y480299D03*
Y475299D03*
Y470299D03*
Y465299D03*
X163335Y460299D03*
Y465299D03*
Y470299D03*
Y475299D03*
Y480299D03*
Y485299D03*
Y490299D03*
Y495299D03*
X258375Y460300D03*
X221225D03*
X258375Y465300D03*
Y470300D03*
Y475300D03*
Y480300D03*
Y485300D03*
Y490300D03*
Y495300D03*
X221225D03*
Y490300D03*
Y485300D03*
Y480300D03*
Y475300D03*
Y470300D03*
Y465300D03*
X267600Y582000D03*
Y587000D03*
Y592000D03*
Y597000D03*
X287600Y592000D03*
Y587000D03*
Y582000D03*
Y597000D03*
X379088Y526681D03*
Y521681D03*
X359088D03*
Y526681D03*
X379088Y536681D03*
Y531681D03*
X359088D03*
Y536681D03*
X648546Y449321D03*
Y454321D03*
Y459321D03*
X668546D03*
Y454321D03*
Y449321D03*
X648546Y464321D03*
X668546D03*
X830300Y388800D03*
Y393800D03*
X850300D03*
Y388800D03*
X830300Y398800D03*
Y403800D03*
X850300D03*
Y398800D03*
G54D17*
X50960Y58330D03*
Y47330D03*
X71090Y63300D03*
Y52300D03*
X632460Y164580D03*
Y153580D03*
X659200Y538200D03*
Y549200D03*
X758435Y410973D03*
Y421973D03*
X767135Y410973D03*
Y421973D03*
X775835Y410973D03*
Y421973D03*
X790300Y452400D03*
Y441400D03*
X749700Y411000D03*
Y422000D03*
X781400Y452400D03*
Y441400D03*
X864928Y382092D03*
Y393092D03*
X873623Y382038D03*
Y393038D03*
G54D53*
X178543Y728500D03*
X156657D03*
G54D119*
X815076Y55812D03*
Y53252D03*
Y50692D03*
X807006D03*
Y53252D03*
Y55812D03*
G54D62*
X297146Y199016D03*
Y195866D03*
Y192717D03*
X314666Y199016D03*
Y195866D03*
Y192717D03*
X297146Y265158D03*
Y262008D03*
Y258858D03*
Y255709D03*
Y252559D03*
Y249410D03*
Y246260D03*
Y243110D03*
Y239961D03*
Y236811D03*
Y233661D03*
Y230512D03*
Y227362D03*
Y224213D03*
Y221063D03*
Y217913D03*
Y214764D03*
Y211614D03*
Y208465D03*
Y205315D03*
Y202165D03*
X314666Y265158D03*
Y262008D03*
Y258858D03*
Y255709D03*
Y252559D03*
Y249410D03*
Y246260D03*
Y243110D03*
Y239961D03*
Y236811D03*
Y233661D03*
Y230512D03*
Y227362D03*
Y224213D03*
Y221063D03*
Y217913D03*
Y214764D03*
Y211614D03*
Y208465D03*
Y205315D03*
Y202165D03*
X297146Y328150D03*
Y325000D03*
Y321850D03*
Y318701D03*
Y315551D03*
Y312402D03*
Y309252D03*
Y306102D03*
Y302953D03*
Y299803D03*
Y296654D03*
Y293504D03*
Y290354D03*
Y287205D03*
Y284055D03*
Y280906D03*
Y277756D03*
Y274606D03*
Y271457D03*
Y268307D03*
X314666Y328150D03*
Y325000D03*
Y321850D03*
Y318701D03*
Y315551D03*
Y312402D03*
Y309252D03*
Y306102D03*
Y302953D03*
Y299803D03*
Y296654D03*
Y293504D03*
Y290354D03*
Y287205D03*
Y284055D03*
Y280906D03*
Y277756D03*
Y274606D03*
Y271457D03*
Y268307D03*
X297146Y378543D03*
Y375394D03*
Y372244D03*
Y369095D03*
Y365945D03*
Y362795D03*
Y359646D03*
Y356496D03*
Y353347D03*
Y350197D03*
Y347047D03*
Y343898D03*
Y340748D03*
Y337599D03*
Y334449D03*
Y331299D03*
X314666Y378543D03*
Y375394D03*
Y372244D03*
Y369095D03*
Y365945D03*
Y362795D03*
Y359646D03*
Y356496D03*
Y353347D03*
Y350197D03*
Y347047D03*
Y343898D03*
Y340748D03*
Y337599D03*
Y334449D03*
Y331299D03*
G54D71*
X372000Y68900D03*
G54D80*
X369969Y580758D03*
X507322Y22393D03*
X502622D03*
X582090Y48880D03*
X646377Y406737D03*
X642660Y562243D03*
X708000Y451700D03*
X675174Y459279D03*
X731076Y595829D03*
X782500Y415200D03*
X762400Y473100D03*
X885562Y307955D03*
X880223Y384817D03*
G54D44*
X154724Y537795D03*
Y540945D03*
Y544094D03*
X157874Y537795D03*
Y540945D03*
Y544094D03*
X161023Y537795D03*
Y540945D03*
Y544094D03*
X154724Y597638D03*
Y600787D03*
Y603937D03*
X157874Y597638D03*
Y600787D03*
Y603937D03*
X161023Y597638D03*
Y600787D03*
Y603937D03*
X214567Y537795D03*
Y540945D03*
Y544094D03*
X217716Y537795D03*
Y540945D03*
Y544094D03*
X220866Y537795D03*
Y540945D03*
Y544094D03*
X214567Y597638D03*
Y600787D03*
Y603937D03*
X217716Y597638D03*
Y600787D03*
Y603937D03*
X220866Y597638D03*
Y600787D03*
Y603937D03*
X713386Y216929D03*
X716535D03*
X719685D03*
X713386Y213779D03*
X716535D03*
X719685D03*
X716535Y210630D03*
X719685D03*
X716535Y301968D03*
X719685D03*
X713386Y298819D03*
X716535D03*
X719685D03*
X713386Y295669D03*
X716535D03*
X719685D03*
X798425Y216929D03*
Y213779D03*
Y210630D03*
Y301968D03*
Y298819D03*
Y295669D03*
X801575Y216929D03*
X804724D03*
X801575Y213779D03*
X804724D03*
X801575Y210630D03*
Y301968D03*
Y298819D03*
X804724D03*
X801575Y295669D03*
X804724D03*
G54D45*
X207900Y637900D03*
X200532Y653603D03*
X215406Y637892D03*
X227500Y642000D03*
X212445Y653488D03*
X272503Y704737D03*
X299900Y582200D03*
X296500D03*
X322277Y548643D03*
X282600Y682100D03*
X345175Y113910D03*
X366632Y192804D03*
X360800Y491700D03*
X477300Y61200D03*
X538250Y68490D03*
X617023Y372365D03*
X679200Y459200D03*
X727676Y587629D03*
X794088Y508612D03*
X763801Y488719D03*
X755300Y500700D03*
X763147Y496327D03*
X747500Y500900D03*
X882871Y236212D03*
G54D18*
X44206Y543876D03*
X36758Y543881D03*
X44187Y555153D03*
X36687D03*
X44000Y549500D03*
X36500D03*
X44206Y538249D03*
X36658Y538254D03*
X44106Y532622D03*
X64746Y647850D03*
X130400Y534600D03*
X140300Y529700D03*
X140424Y538335D03*
X130400Y530300D03*
X123403Y609818D03*
X126397Y601923D03*
X126100Y632300D03*
Y636400D03*
X200800Y502800D03*
X182920Y473998D03*
X156800Y648400D03*
X148549Y683715D03*
X158549Y711215D03*
X212100Y495300D03*
X271300Y474500D03*
X251466Y567108D03*
X251100Y573500D03*
X250850Y578300D03*
X243700Y588900D03*
X243010Y537139D03*
X251100Y585700D03*
X242970Y552558D03*
X264200Y539500D03*
X267600Y552100D03*
X243996Y560698D03*
Y564798D03*
X258274Y552061D03*
X251396Y556761D03*
X251477Y563068D03*
X228016Y658967D03*
X238200Y633200D03*
X243300Y601000D03*
X263273Y634343D03*
X275420Y718920D03*
X238900Y659100D03*
X261719Y662209D03*
X302432Y578108D03*
X277700Y575000D03*
X296800Y573700D03*
X297500Y569700D03*
X295100Y565600D03*
X302600Y564200D03*
X302876Y557611D03*
X316033Y535357D03*
X305448Y620477D03*
X285360Y647950D03*
Y652100D03*
X294782Y691947D03*
X345629Y193678D03*
X370372Y245284D03*
X343617Y231156D03*
X343659Y261112D03*
X370242Y224934D03*
X370472Y240684D03*
X345378Y517086D03*
X351261Y507831D03*
X358030Y481570D03*
X348700Y545100D03*
X389700Y568500D03*
X391181Y623786D03*
X391100Y610300D03*
X366064Y635920D03*
X490000Y49100D03*
X493200Y34000D03*
X485800Y67973D03*
X485925Y58850D03*
X596900Y373300D03*
X607708Y373437D03*
X633722Y375305D03*
X649800Y504100D03*
X642860Y549543D03*
X699920Y197740D03*
X688500Y255400D03*
X700000Y244800D03*
X685400Y249100D03*
X697300Y228400D03*
Y232400D03*
Y236850D03*
X684847Y240430D03*
X689000Y265100D03*
X688600Y259500D03*
X699403Y211743D03*
X699550Y203560D03*
X688947Y277530D03*
Y269230D03*
X688800Y285900D03*
X688947Y281730D03*
X686200Y307000D03*
X688947Y273430D03*
X674550Y470684D03*
X675900Y503900D03*
X699400Y504000D03*
X706538Y553602D03*
X722000Y569100D03*
X711200Y614500D03*
X719576Y594029D03*
X757720Y126510D03*
X785954Y514350D03*
X788684Y505600D03*
X780700Y518500D03*
X771019Y488799D03*
X747200Y508600D03*
X823200Y322500D03*
X809334Y480900D03*
X868950Y403400D03*
G54D36*
X135012Y521048D03*
X125788D03*
X135012Y514552D03*
X125788D03*
X270521Y612019D03*
Y618515D03*
X279745Y612019D03*
Y618515D03*
G54D90*
X457950Y28510D03*
Y42290D03*
X478050D03*
Y28510D03*
G54D27*
X70832Y656107D03*
X68273D03*
X65714D03*
X63155D03*
X60596D03*
Y675593D03*
X63155D03*
X65714D03*
X68273D03*
X70832D03*
X311418Y628857D03*
X308859D03*
X306300D03*
X303741D03*
X301182D03*
Y648343D03*
X303741D03*
X306300D03*
X308859D03*
X311418D03*
X300752Y700327D03*
X298193D03*
X295634D03*
X293075D03*
X290516D03*
Y719813D03*
X293075D03*
X295634D03*
X298193D03*
X300752D03*
X815332Y490107D03*
X812773D03*
X810214D03*
X807655D03*
X805096D03*
Y509593D03*
X807655D03*
X810214D03*
X812773D03*
X815332D03*
G54D54*
X274245Y551954D03*
Y549394D03*
Y546834D03*
X281645D03*
Y549394D03*
Y551954D03*
G54D63*
X305070Y522451D03*
Y525011D03*
X317870D03*
Y522451D03*
X305070Y527571D03*
Y530131D03*
X317870D03*
Y527571D03*
X313821Y556747D03*
Y559307D03*
Y561867D03*
Y564427D03*
Y566987D03*
Y569547D03*
Y572107D03*
Y574667D03*
Y577227D03*
Y579787D03*
X336021D03*
Y577227D03*
Y574667D03*
Y572107D03*
Y569547D03*
Y566987D03*
Y564427D03*
Y561867D03*
Y559307D03*
Y556747D03*
X355739Y575709D03*
Y573149D03*
Y570589D03*
Y568029D03*
Y565469D03*
Y562909D03*
Y560349D03*
Y557789D03*
Y555229D03*
Y552669D03*
Y550109D03*
Y547549D03*
X377939D03*
Y550109D03*
Y552669D03*
Y555229D03*
Y557789D03*
Y560349D03*
Y562909D03*
Y565469D03*
Y568029D03*
Y570589D03*
Y573149D03*
Y575709D03*
X374610Y695500D03*
Y692940D03*
Y690380D03*
Y687820D03*
Y685260D03*
Y682700D03*
Y680140D03*
Y677580D03*
Y675020D03*
Y672460D03*
X352410D03*
Y675020D03*
Y677580D03*
Y680140D03*
Y682700D03*
Y685260D03*
Y687820D03*
Y690380D03*
Y692940D03*
Y695500D03*
G54D81*
X369969Y586358D03*
X507322Y27993D03*
X502622D03*
X582090Y54480D03*
X646377Y412337D03*
X642660Y567843D03*
X708000Y457300D03*
X675174Y464879D03*
X731076Y601429D03*
X782500Y420800D03*
X762400Y478700D03*
X885562Y313555D03*
X880223Y390417D03*
G54D72*
X372000Y62500D03*
X344958Y107078D03*
G54D19*
X40806Y543876D03*
X33358Y543881D03*
X40787Y555153D03*
X33287D03*
X40600Y549500D03*
X33100D03*
X40806Y538249D03*
X33258Y538254D03*
X40706Y532622D03*
X61346Y647850D03*
X127000Y534600D03*
X136900Y529700D03*
X137024Y538335D03*
X127000Y530300D03*
X120003Y609818D03*
X122997Y601923D03*
X122700Y632300D03*
Y636400D03*
X208700Y495300D03*
X197400Y502800D03*
X179520Y473998D03*
X153400Y648400D03*
X145149Y683715D03*
X155149Y711215D03*
X267900Y474500D03*
X248066Y567108D03*
X247700Y573500D03*
X247450Y578300D03*
X240300Y588900D03*
X239610Y537139D03*
X247700Y585700D03*
X239570Y552558D03*
X260800Y539500D03*
X264200Y552100D03*
X240596Y560698D03*
Y564798D03*
X254874Y552061D03*
X247996Y556761D03*
X248077Y563068D03*
X274300Y575000D03*
X224616Y658967D03*
X234800Y633200D03*
X239900Y601000D03*
X259873Y634343D03*
X272020Y718920D03*
X235500Y659100D03*
X258319Y662209D03*
X340217Y231156D03*
X340259Y261112D03*
X299032Y578108D03*
X293400Y573700D03*
X294100Y569700D03*
X291700Y565600D03*
X299200Y564200D03*
X299476Y557611D03*
X312633Y535357D03*
X302048Y620477D03*
X281960Y647950D03*
Y652100D03*
X291382Y691947D03*
X342229Y193678D03*
X366972Y245284D03*
X366842Y224934D03*
X367072Y240684D03*
X341978Y517086D03*
X347861Y507831D03*
X354630Y481570D03*
X345300Y545100D03*
X386300Y568500D03*
X387781Y623786D03*
X387700Y610300D03*
X362664Y635920D03*
X486600Y49100D03*
X489800Y34000D03*
X482400Y67973D03*
X482525Y58850D03*
X593500Y373300D03*
X604308Y373437D03*
X630322Y375305D03*
X646400Y504100D03*
X639460Y549543D03*
X696520Y197740D03*
X685100Y255400D03*
X696600Y244800D03*
X682000Y249100D03*
X693900Y228400D03*
Y232400D03*
Y236850D03*
X681447Y240430D03*
X685600Y265100D03*
X685200Y259500D03*
X696003Y211743D03*
X696150Y203560D03*
X685547Y277530D03*
Y269230D03*
X685400Y285900D03*
X685547Y281730D03*
X682800Y307000D03*
X685547Y273430D03*
X671150Y470684D03*
X672500Y503900D03*
X696000Y504000D03*
X703138Y553602D03*
X718600Y569100D03*
X707800Y614500D03*
X716176Y594029D03*
X754320Y126510D03*
X782554Y514350D03*
X785284Y505600D03*
X777300Y518500D03*
X767619Y488799D03*
X743800Y508600D03*
X819800Y322500D03*
X805934Y480900D03*
X865550Y403400D03*
G54D73*
X372000Y65500D03*
X344958Y110078D03*
G54D46*
X207900Y641500D03*
X200532Y657203D03*
X215406Y641492D03*
X227500Y645600D03*
X212445Y657088D03*
X272503Y708337D03*
X299900Y585800D03*
X296500D03*
X322277Y552243D03*
X282600Y685700D03*
X345175Y117510D03*
X366632Y196404D03*
X360800Y495300D03*
X477300Y64800D03*
X538250Y72090D03*
X617023Y375965D03*
X679200Y462800D03*
X727676Y591229D03*
X794088Y512212D03*
X763801Y492319D03*
X755300Y504300D03*
X763147Y499927D03*
X747500Y504500D03*
X882871Y239812D03*
G54D55*
X267250Y652500D03*
X259750Y648625D03*
Y656375D03*
X696100Y489716D03*
X688600Y493591D03*
Y485841D03*
X680250Y489500D03*
X672750Y493375D03*
Y485625D03*
X829970Y61300D03*
X822470Y65175D03*
Y57425D03*
G54D37*
X90854Y639150D03*
X98454D03*
X90854Y647050D03*
X98454D03*
X87050Y682154D03*
X94650D03*
X87100Y674400D03*
X94700D03*
X87900Y722700D03*
X95500D03*
X322740Y611500D03*
X330340D03*
X322740Y619400D03*
X330340D03*
X320774Y691270D03*
X328374D03*
X320774Y683370D03*
X328374D03*
X352200Y105700D03*
X359800D03*
X512857Y25444D03*
X520457D03*
X511349Y34452D03*
X503749D03*
Y42252D03*
X511349D03*
X602860Y528543D03*
X667600Y436900D03*
X660000D03*
X622300Y473000D03*
X614700D03*
X622300Y481000D03*
X614700D03*
X610460Y528543D03*
X669300Y704200D03*
X661700D03*
X669300Y696500D03*
X661700D03*
X669300Y688800D03*
X661700D03*
X721300Y433500D03*
X728900D03*
X721300Y441300D03*
X728900D03*
X721300Y449100D03*
X728900D03*
X721300Y456900D03*
X728900D03*
X721300Y464700D03*
X728900D03*
X684700Y536600D03*
X677100D03*
X683000Y567400D03*
X675400D03*
X684676Y559729D03*
X677076D03*
X684676Y544329D03*
X677076D03*
X684676Y552029D03*
X677076D03*
X683276Y579571D03*
X675676D03*
X835654Y481650D03*
X843254D03*
X835900Y469500D03*
X843500D03*
G54D64*
X320750Y592060D03*
Y589500D03*
Y586940D03*
X327250D03*
Y592060D03*
G54D82*
X369273Y645871D03*
X360049D03*
Y651827D03*
X369273D03*
G54D91*
X458250Y30479D03*
Y32447D03*
Y34416D03*
Y36384D03*
Y38353D03*
Y40321D03*
X477750D03*
Y38353D03*
Y36384D03*
Y34416D03*
Y32447D03*
Y30479D03*
G54D28*
X43800Y660700D03*
X179518Y463748D03*
X145049Y687715D03*
X268300Y465400D03*
X251500Y590200D03*
X259707Y626253D03*
X268800Y639000D03*
X259100Y666100D03*
X325086Y522525D03*
X334200Y592000D03*
X278473Y637655D03*
X342100Y189874D03*
X366614Y639820D03*
X385170Y697180D03*
X468216Y53745D03*
X489786Y37907D03*
X774000Y66000D03*
X765900Y113000D03*
X837600Y475500D03*
G54D92*
X468000Y35400D03*
G54D83*
X357290Y624270D03*
X373038D03*
Y600970D03*
X357290D03*
G54D65*
X315252Y546325D03*
Y544355D03*
Y542385D03*
Y540415D03*
X306052D03*
Y542385D03*
Y544355D03*
Y546325D03*
X377739Y513804D03*
Y511839D03*
Y509869D03*
Y507899D03*
Y505934D03*
X361439D03*
Y507899D03*
Y509869D03*
Y511839D03*
Y513804D03*
G36*
G01X175989Y669266D02*
G02Y669316I-12800J25D01*
G01X171589D01*
G03Y669266I-8400J-25D01*
G01X175989D01*
G37*
G54D74*
X374800Y111000D03*
Y116000D03*
Y121000D03*
X652500Y499600D03*
X651200Y545100D03*
X649900Y540300D03*
X713800Y619000D03*
X722100Y603700D03*
X772555Y39735D03*
X768300Y483800D03*
G54D29*
X47400Y660700D03*
X183118Y463748D03*
X148649Y687715D03*
X271900Y465400D03*
X255100Y590200D03*
X263307Y626253D03*
X272400Y639000D03*
X262700Y666100D03*
X328686Y522525D03*
X337800Y592000D03*
X282073Y637655D03*
X345700Y189874D03*
X370214Y639820D03*
X388770Y697180D03*
X471816Y53745D03*
X493386Y37907D03*
X777600Y66000D03*
X769500Y113000D03*
X841200Y475500D03*
G54D56*
X244750Y652500D03*
X252250Y656375D03*
Y648625D03*
X244750Y666500D03*
X252250Y662625D03*
Y670375D03*
X359976Y183681D03*
X367476Y179806D03*
Y187556D03*
X491740Y63670D03*
X499240Y67545D03*
Y59795D03*
X683000Y473384D03*
X690500Y469509D03*
Y477259D03*
G54D38*
X140500Y620300D03*
X208000Y520500D03*
X208100Y515200D03*
X202800Y509900D03*
X174100Y628900D03*
X168800Y628400D03*
X159200Y623240D03*
X164130Y625550D03*
X168300Y621900D03*
X158350Y629040D03*
X181540Y644450D03*
X217100Y520300D03*
X238200Y524600D03*
X235562Y541096D03*
X249998Y550219D03*
X246800Y541900D03*
X241100Y541600D03*
X240900Y547300D03*
X235500Y548200D03*
X226168Y618952D03*
X235600Y611800D03*
X368500Y591900D03*
X519900Y103150D03*
X533080Y108300D03*
X520000Y108700D03*
X594000Y151500D03*
X600000D03*
X587300Y151400D03*
X616300D03*
X610900Y151500D03*
X605400Y151400D03*
X622310Y157470D03*
X621600Y151600D03*
X730000Y196800D03*
X724700D03*
X681700Y155600D03*
X678100Y151500D03*
X697400Y155500D03*
X693400Y151700D03*
X689400Y155500D03*
X705300Y155100D03*
X685600Y151400D03*
X701100Y151600D03*
X726000Y322000D03*
X720613Y321539D03*
X693300Y297000D03*
X691200Y306300D03*
X706300Y319900D03*
X696000Y311100D03*
X699000Y290100D03*
X696200Y301700D03*
X713400Y316800D03*
X699300Y306900D03*
X732000Y341400D03*
X732600Y346900D03*
X722500Y341000D03*
X787900Y196700D03*
X793200D03*
X798700D03*
X775600D03*
X780500Y190500D03*
X782500Y196800D03*
X770300Y196700D03*
X758947Y196761D03*
X735500Y196800D03*
X740900Y196750D03*
X752922Y196789D03*
X738586Y340730D03*
X810500Y196700D03*
X804600D03*
G54D48*
X153549Y687715D03*
X434500Y52457D03*
Y42657D03*
Y47557D03*
X629860Y521543D03*
X703400Y558300D03*
X795224Y42000D03*
X821224D03*
G54D57*
X263491Y692574D03*
X260931D03*
X258371D03*
Y686074D03*
X263491D03*
X251091Y692774D03*
X248531D03*
X245971D03*
Y686274D03*
X251091D03*
X271240Y686350D03*
X273800D03*
X271240Y692850D03*
X276360Y686350D03*
Y692850D03*
X369095Y217923D03*
X366535D03*
X363975D03*
Y211423D03*
X369095D03*
X366340Y487050D03*
X368900D03*
X371460D03*
Y493550D03*
X366340D03*
X557660Y60130D03*
X555100D03*
X552540D03*
Y53630D03*
X557660D03*
X707944Y470930D03*
X705384D03*
X702824D03*
Y464430D03*
X707944D03*
X783860Y47062D03*
X786420D03*
X788980D03*
Y53562D03*
X783860D03*
X762740Y99750D03*
X765300D03*
X767860D03*
Y106250D03*
X762740D03*
X772060Y78750D03*
X769500D03*
X766940D03*
Y72250D03*
X772060D03*
G54D93*
X535048Y54803D03*
Y48397D03*
G54D84*
X376814Y620494D03*
Y604746D03*
X353514D03*
Y620494D03*
G54D75*
X369200Y111000D03*
Y116000D03*
Y121000D03*
X646900Y499600D03*
X645600Y545100D03*
X644300Y540300D03*
X708200Y619000D03*
X716500Y603700D03*
X766955Y39735D03*
X762700Y483800D03*
G54D66*
X327561Y656480D03*
X335311D03*
X331436Y663980D03*
X343006Y656555D03*
X350756D03*
X346881Y664055D03*
X555625Y68750D03*
X563375D03*
X559500Y76250D03*
X642345Y391494D03*
X650095D03*
X646220Y398994D03*
X783125Y66750D03*
X790875D03*
X786750Y93550D03*
X782875Y86050D03*
X790625D03*
X787000Y74250D03*
X785600Y117600D03*
X781725Y110100D03*
X789475D03*
X897344Y306791D03*
X893469Y299291D03*
X901219D03*
G54D39*
X135522Y628682D03*
X83000Y734600D03*
X252107Y516929D03*
X689237Y325511D03*
X838300Y36700D03*
X820896Y207364D03*
X888800Y696900D03*
G54D67*
X299900Y657300D03*
Y660900D03*
G54D94*
X529093Y39585D03*
Y34585D03*
Y29585D03*
Y24585D03*
G54D76*
X360500Y112960D03*
Y116700D03*
Y120440D03*
X351500D03*
Y112960D03*
X369500Y702460D03*
Y706200D03*
Y709940D03*
X360500D03*
Y702460D03*
G54D85*
X359258Y623920D03*
X361227D03*
X363195D03*
X365164D03*
X367133D03*
X369101D03*
X371070D03*
Y601320D03*
X369101D03*
X367133D03*
X365164D03*
X363195D03*
X361227D03*
X359258D03*
G54D58*
X230315Y679921D03*
G54D49*
X159149Y687715D03*
X440100Y52457D03*
Y42657D03*
Y47557D03*
X635460Y521543D03*
X709000Y558300D03*
X826824Y42000D03*
X800824D03*
G54D59*
X258800Y669800D03*
X262400D03*
X662100Y429900D03*
X665700D03*
X662100Y409400D03*
X665700D03*
X662100Y413500D03*
X665700D03*
X662100Y417600D03*
X665700D03*
X662100Y421700D03*
X665700D03*
X662100Y425800D03*
X665700D03*
G54D95*
X525520Y63570D03*
Y77410D03*
X710330Y497490D03*
Y483650D03*
G54D68*
X390527Y67190D03*
X386727D03*
X390527Y73790D03*
X386727D03*
G54D86*
X376464Y618526D03*
Y616557D03*
Y614589D03*
Y612620D03*
Y610651D03*
Y608683D03*
Y606714D03*
X353864D03*
Y608683D03*
Y610651D03*
Y612620D03*
Y614589D03*
Y616557D03*
Y618526D03*
G54D77*
X372000Y71900D03*
G54D87*
X365164Y612620D03*
G54D78*
X356611Y200364D03*
X351611D03*
X346611D03*
X341611D03*
Y220364D03*
X346611D03*
X351611D03*
X356611D03*
G54D96*
X542550Y54803D03*
Y48397D03*
G54D69*
X371768Y53823D03*
Y49223D03*
X371594Y84695D03*
Y80095D03*
G54D79*
X368412Y232724D03*
X354572D03*
G54D97*
X576160Y54765D03*
X573600D03*
X571040D03*
Y62835D03*
X573600D03*
X576160D03*
X765260Y50010D03*
X762700D03*
X760140D03*
Y58080D03*
X762700D03*
X765260D03*
G54D88*
X461110Y45450D03*
Y25350D03*
X474890Y45450D03*
Y25350D03*
G54D98*
X599998Y386961D03*
X589873Y379461D03*
X593748Y386961D03*
X585998D03*
X603873Y379461D03*
X607748Y386961D03*
X767684Y524500D03*
X786584Y525000D03*
X771559Y532000D03*
X763809D03*
X790459Y532500D03*
X782709D03*
G54D89*
X463079Y45150D03*
X465047D03*
X467016D03*
X468984D03*
X470953D03*
Y25650D03*
X468984D03*
X467016D03*
X465047D03*
X463079D03*
X472921Y45150D03*
Y25650D03*
G54D99*
X625894Y360600D03*
X628454D03*
X631014D03*
X633574D03*
Y347800D03*
X631014D03*
X628454D03*
X625894D03*
M02*
